FILE_TYPE = MACRO_DRAWING;
SET COLOR_WIRE YELLOW;
SET COLOR_PROP MONO;
SET COLOR_DOT WHITE;
SET COLOR_ARC YELLOW;
SET COLOR_BODY GREEN;
SET COLOR_NOTE MONO;
SET PROP_DISPLAY VALUE;
SET PAGE_NUMBER P132;
FORCEADD CAP_A..1
(2575 4475);
FORCEPROP 1 LAST LOCATION C3L25
J 0
(2625 4575);
DISPLAY 0.617021 (2625 4575);
PAINT AQUA (2625 4575);
FORCEPROP 1 LAST PART_NUMBER E15431-004
J 0
(2625 4325);
DISPLAY 0.617021 (2625 4325);
PAINT BLUE (2625 4325);
FORCEPROP 1 LAST VALUE 22.0UF
J 0
(2625 4525);
DISPLAY 0.617021 (2625 4525);
PAINT SKYBLUE (2625 4525);
FORCEPROP 1 LAST TOLERANCE 20%
J 0
(2625 4425);
DISPLAY 0.617021 (2625 4425);
PAINT SKYBLUE (2625 4425);
FORCEPROP 1 LAST PACK_TYPE 0603V
J 0
(2625 4275);
DISPLAY 0.617021 (2625 4275);
PAINT SKYBLUE (2625 4275);
FORCEPROP 1 LAST VOLTAGE 4V
J 0
(2625 4475);
DISPLAY 0.617021 (2625 4475);
PAINT SKYBLUE (2625 4475);
FORCEPROP 1 LAST MATERIAL X6S
J 0
(2625 4375);
DISPLAY 0.617021 (2625 4375);
PAINT SKYBLUE (2625 4375);
FORCEPROP 1 LASTPIN (2575 4575) $PN 1
J 0
(2585 4555);
DISPLAY 0.617021 (2585 4555);
PAINT WHITE (2585 4555);
FORCEPROP 1 LASTPIN (2575 4375) $PN 2
J 0
(2585 4355);
DISPLAY 0.617021 (2585 4355);
PAINT WHITE (2585 4355);
FORCEPROP 2 LAST CDS_LOCATION C3L25
J 0
(2625 4575);
DISPLAY 0.617021 (2625 4575);
PAINT AQUA (2625 4575);
DISPLAY INVISIBLE (2625 4575);
FORCEPROP 2 LAST BOM_COST SB
J 0
(2625 4675);
DISPLAY 1.361702 (2625 4675);
PAINT ORANGE (2625 4675);
DISPLAY INVISIBLE (2625 4675);
FORCEPROP 2 LAST CDS_LIB dev_discrete
J 0
(2575 4475);
PAINT ORANGE (2575 4475);
DISPLAY INVISIBLE (2575 4475);
FORCEPROP 2 LAST CDS_SEC 1
J 0
(2625 4675);
DISPLAY 1.361702 (2625 4675);
PAINT ORANGE (2625 4675);
DISPLAY INVISIBLE (2625 4675);
FORCEPROP 2 LAST $SEC 1
J 0
(2625 4675);
DISPLAY 0.914894 (2625 4675);
PAINT MONO (2625 4675);
DISPLAY INVISIBLE (2625 4675);
FORCEPROP 1 LAST PATH I1
J 0
(2625 4625);
DISPLAY 0.978723 (2625 4625);
PAINT WHITE (2625 4625);
DISPLAY INVISIBLE (2625 4625);
FORCEPROP 2 LAST ROOM SB_DECOUPLING
J 0
(2625 4625);
DISPLAY 1.361702 (2625 4625);
PAINT ORANGE (2625 4625);
DISPLAY INVISIBLE (2625 4625);
FORCEADD GND..1
(2050 4150);
FORCEPROP 3 LASTPIN (2050 4200) SIG_NAME GND\g
J 0
(2060 4210);
DISPLAY 0.659574 (2060 4210);
PAINT MONO (2060 4210);
DISPLAY INVISIBLE (2060 4210);
FORCEPROP 1 LAST VOLTAGE 0.0V
J 0
(2005 4107);
DISPLAY 0.340426 (2005 4107);
PAINT SKYBLUE (2005 4107);
DISPLAY INVISIBLE (2005 4107);
FORCEPROP 2 LAST BOM_COST SB
J 0
(2075 4225);
DISPLAY 1.361702 (2075 4225);
PAINT ORANGE (2075 4225);
DISPLAY INVISIBLE (2075 4225);
FORCEPROP 1 LAST SIZE 1B
J 0
(2125 4100);
DISPLAY 1.170213 (2125 4100);
PAINT AQUA (2125 4100);
DISPLAY INVISIBLE (2125 4100);
FORCEPROP 2 LAST CDS_LIB mstr_symbols
J 0
(2050 4150);
PAINT MONO (2050 4150);
DISPLAY INVISIBLE (2050 4150);
FORCEPROP 1 LAST BODY_TYPE PLUMBING
J 0
(2005 4107);
DISPLAY 0.340426 (2005 4107);
PAINT GREEN (2005 4107);
DISPLAY INVISIBLE (2005 4107);
FORCEPROP 1 LAST PATH I10
J 0
(2125 4150);
DISPLAY 0.872340 (2125 4150);
PAINT AQUA (2125 4150);
DISPLAY INVISIBLE (2125 4150);
FORCEPROP 2 LAST ROOM SB_DECOUPLING
J 0
(2075 4225);
DISPLAY 1.361702 (2075 4225);
PAINT ORANGE (2075 4225);
DISPLAY INVISIBLE (2075 4225);
FORCEPROP 1 LAST HDL_POWER GND
J 0
(2050 4300);
DISPLAY 1.170213 (2050 4300);
PAINT GREEN (2050 4300);
DISPLAY INVISIBLE (2050 4300);
FORCEADD CAP_A..1
(2200 3500);
FORCEPROP 1 LAST LOCATION C7A36
J 0
(2250 3600);
DISPLAY 0.617021 (2250 3600);
PAINT AQUA (2250 3600);
FORCEPROP 1 LAST PART_NUMBER E15431-004
J 0
(2250 3350);
DISPLAY 0.617021 (2250 3350);
PAINT BLUE (2250 3350);
FORCEPROP 1 LAST VALUE 22.0UF
J 0
(2250 3550);
DISPLAY 0.617021 (2250 3550);
PAINT SKYBLUE (2250 3550);
FORCEPROP 1 LAST TOLERANCE 20%
J 0
(2250 3450);
DISPLAY 0.617021 (2250 3450);
PAINT SKYBLUE (2250 3450);
FORCEPROP 1 LAST PACK_TYPE 0603V
J 0
(2250 3300);
DISPLAY 0.617021 (2250 3300);
PAINT SKYBLUE (2250 3300);
FORCEPROP 1 LAST VOLTAGE 4V
J 0
(2250 3500);
DISPLAY 0.617021 (2250 3500);
PAINT SKYBLUE (2250 3500);
FORCEPROP 1 LAST MATERIAL X6S
J 0
(2250 3400);
DISPLAY 0.617021 (2250 3400);
PAINT SKYBLUE (2250 3400);
FORCEPROP 2 LAST CDS_LOCATION C7A36
J 0
(2250 3600);
DISPLAY 0.617021 (2250 3600);
PAINT AQUA (2250 3600);
DISPLAY INVISIBLE (2250 3600);
FORCEPROP 2 LAST BOM_COST SB
J 0
(2250 3250);
PAINT MONO (2250 3250);
DISPLAY INVISIBLE (2250 3250);
FORCEPROP 2 LAST CDS_LIB dev_discrete
J 0
(2200 3500);
PAINT ORANGE (2200 3500);
DISPLAY INVISIBLE (2200 3500);
FORCEPROP 2 LAST CDS_SEC 1
J 0
(2250 3700);
DISPLAY 1.361702 (2250 3700);
PAINT ORANGE (2250 3700);
DISPLAY INVISIBLE (2250 3700);
FORCEPROP 2 LAST $SEC 1
J 0
(2250 3700);
DISPLAY 0.914894 (2250 3700);
PAINT MONO (2250 3700);
DISPLAY INVISIBLE (2250 3700);
FORCEPROP 1 LAST PATH I11
J 0
(2250 3650);
DISPLAY 0.978723 (2250 3650);
PAINT WHITE (2250 3650);
DISPLAY INVISIBLE (2250 3650);
FORCEPROP 2 LAST ROOM SB_DECOUPLING
J 0
(2200 3500);
PAINT WHITE (2200 3500);
DISPLAY INVISIBLE (2200 3500);
FORCEPROP 1 LASTPIN (2200 3600) $PN 1
J 0
(2210 3580);
DISPLAY 1.063830 (2210 3580);
PAINT WHITE (2210 3580);
DISPLAY INVISIBLE (2210 3580);
FORCEPROP 1 LASTPIN (2200 3400) $PN 2
J 0
(2210 3380);
DISPLAY 1.063830 (2210 3380);
PAINT WHITE (2210 3380);
DISPLAY INVISIBLE (2210 3380);
FORCEADD CAP_A..1
(1825 3500);
FORCEPROP 1 LAST LOCATION C3N12
J 0
(1875 3600);
DISPLAY 0.617021 (1875 3600);
PAINT AQUA (1875 3600);
FORCEPROP 1 LAST PART_NUMBER E15431-004
J 0
(1875 3350);
DISPLAY 0.617021 (1875 3350);
PAINT BLUE (1875 3350);
FORCEPROP 1 LAST VALUE 22.0UF
J 0
(1875 3550);
DISPLAY 0.617021 (1875 3550);
PAINT SKYBLUE (1875 3550);
FORCEPROP 1 LAST TOLERANCE 20%
J 0
(1875 3450);
DISPLAY 0.617021 (1875 3450);
PAINT SKYBLUE (1875 3450);
FORCEPROP 1 LAST PACK_TYPE 0603V
J 0
(1875 3300);
DISPLAY 0.617021 (1875 3300);
PAINT SKYBLUE (1875 3300);
FORCEPROP 1 LAST VOLTAGE 4V
J 0
(1875 3500);
DISPLAY 0.617021 (1875 3500);
PAINT SKYBLUE (1875 3500);
FORCEPROP 1 LAST MATERIAL X6S
J 0
(1875 3400);
DISPLAY 0.617021 (1875 3400);
PAINT SKYBLUE (1875 3400);
FORCEPROP 2 LAST CDS_LOCATION C3N12
J 0
(1875 3600);
DISPLAY 0.617021 (1875 3600);
PAINT AQUA (1875 3600);
DISPLAY INVISIBLE (1875 3600);
FORCEPROP 2 LAST BOM_COST SB
J 0
(1875 3250);
PAINT MONO (1875 3250);
DISPLAY INVISIBLE (1875 3250);
FORCEPROP 2 LAST CDS_LIB dev_discrete
J 0
(1825 3500);
PAINT ORANGE (1825 3500);
DISPLAY INVISIBLE (1825 3500);
FORCEPROP 2 LAST CDS_SEC 1
J 0
(1875 3700);
DISPLAY 1.361702 (1875 3700);
PAINT ORANGE (1875 3700);
DISPLAY INVISIBLE (1875 3700);
FORCEPROP 2 LAST $SEC 1
J 0
(1875 3700);
DISPLAY 0.914894 (1875 3700);
PAINT MONO (1875 3700);
DISPLAY INVISIBLE (1875 3700);
FORCEPROP 1 LAST PATH I12
J 0
(1875 3650);
DISPLAY 0.978723 (1875 3650);
PAINT WHITE (1875 3650);
DISPLAY INVISIBLE (1875 3650);
FORCEPROP 2 LAST ROOM SB_DECOUPLING
J 0
(1825 3500);
PAINT WHITE (1825 3500);
DISPLAY INVISIBLE (1825 3500);
FORCEPROP 1 LASTPIN (1825 3600) $PN 1
J 0
(1835 3580);
DISPLAY 1.063830 (1835 3580);
PAINT WHITE (1835 3580);
DISPLAY INVISIBLE (1835 3580);
FORCEPROP 1 LASTPIN (1825 3400) $PN 2
J 0
(1835 3380);
DISPLAY 1.063830 (1835 3380);
PAINT WHITE (1835 3380);
DISPLAY INVISIBLE (1835 3380);
FORCEADD CAP_A..1
(1450 3500);
FORCEPROP 1 LAST LOCATION C3N10
J 0
(1500 3600);
DISPLAY 0.617021 (1500 3600);
PAINT AQUA (1500 3600);
FORCEPROP 1 LAST PART_NUMBER E15431-004
J 0
(1500 3350);
DISPLAY 0.617021 (1500 3350);
PAINT BLUE (1500 3350);
FORCEPROP 1 LAST VALUE 22.0UF
J 0
(1500 3550);
DISPLAY 0.617021 (1500 3550);
PAINT SKYBLUE (1500 3550);
FORCEPROP 1 LAST TOLERANCE 20%
J 0
(1500 3450);
DISPLAY 0.617021 (1500 3450);
PAINT SKYBLUE (1500 3450);
FORCEPROP 1 LAST PACK_TYPE 0603V
J 0
(1500 3300);
DISPLAY 0.617021 (1500 3300);
PAINT SKYBLUE (1500 3300);
FORCEPROP 1 LAST VOLTAGE 4V
J 0
(1500 3500);
DISPLAY 0.617021 (1500 3500);
PAINT SKYBLUE (1500 3500);
FORCEPROP 1 LAST MATERIAL X6S
J 0
(1500 3400);
DISPLAY 0.617021 (1500 3400);
PAINT SKYBLUE (1500 3400);
FORCEPROP 2 LAST CDS_LOCATION C3N10
J 0
(1500 3600);
DISPLAY 0.617021 (1500 3600);
PAINT AQUA (1500 3600);
DISPLAY INVISIBLE (1500 3600);
FORCEPROP 2 LAST BOM_COST SB
J 0
(1500 3250);
PAINT MONO (1500 3250);
DISPLAY INVISIBLE (1500 3250);
FORCEPROP 2 LAST CDS_LIB dev_discrete
J 0
(1450 3500);
PAINT ORANGE (1450 3500);
DISPLAY INVISIBLE (1450 3500);
FORCEPROP 2 LAST CDS_SEC 1
J 0
(1500 3700);
DISPLAY 1.361702 (1500 3700);
PAINT ORANGE (1500 3700);
DISPLAY INVISIBLE (1500 3700);
FORCEPROP 2 LAST $SEC 1
J 0
(1500 3700);
DISPLAY 0.914894 (1500 3700);
PAINT MONO (1500 3700);
DISPLAY INVISIBLE (1500 3700);
FORCEPROP 1 LAST PATH I13
J 0
(1500 3650);
DISPLAY 0.978723 (1500 3650);
PAINT WHITE (1500 3650);
DISPLAY INVISIBLE (1500 3650);
FORCEPROP 2 LAST ROOM SB_DECOUPLING
J 0
(1450 3500);
PAINT WHITE (1450 3500);
DISPLAY INVISIBLE (1450 3500);
FORCEPROP 1 LASTPIN (1450 3600) $PN 1
J 0
(1460 3580);
DISPLAY 1.063830 (1460 3580);
PAINT WHITE (1460 3580);
DISPLAY INVISIBLE (1460 3580);
FORCEPROP 1 LASTPIN (1450 3400) $PN 2
J 0
(1460 3380);
DISPLAY 1.063830 (1460 3380);
PAINT WHITE (1460 3380);
DISPLAY INVISIBLE (1460 3380);
FORCEADD PVNN_PCH_STBY..1
(1350 3750);
FORCEPROP 3 LASTPIN (1350 3700) SIG_NAME PVNN_PCH_STBY\g
J 0
(1360 3710);
DISPLAY 0.659574 (1360 3710);
PAINT MONO (1360 3710);
DISPLAY INVISIBLE (1360 3710);
FORCEPROP 1 LAST VOLTAGE 1.0V
J 0
(1305 3707);
DISPLAY 0.340426 (1305 3707);
PAINT SKYBLUE (1305 3707);
DISPLAY INVISIBLE (1305 3707);
FORCEPROP 2 LAST CDS_LIB mstr_symbols
J 0
(1350 3750);
PAINT ORANGE (1350 3750);
DISPLAY INVISIBLE (1350 3750);
FORCEPROP 2 LAST BOM_COST SB
J 0
(1350 3850);
DISPLAY 1.361702 (1350 3850);
PAINT ORANGE (1350 3850);
DISPLAY INVISIBLE (1350 3850);
FORCEPROP 1 LAST BODY_TYPE PLUMBING
J 0
(1305 3707);
DISPLAY 0.340426 (1305 3707);
PAINT GREEN (1305 3707);
DISPLAY INVISIBLE (1305 3707);
FORCEPROP 1 LAST PATH I14
J 0
(1400 3775);
DISPLAY 0.872340 (1400 3775);
PAINT AQUA (1400 3775);
DISPLAY INVISIBLE (1400 3775);
FORCEPROP 2 LAST ROOM SB_DECOUPLING
J 0
(1350 3850);
DISPLAY 1.361702 (1350 3850);
PAINT WHITE (1350 3850);
DISPLAY INVISIBLE (1350 3850);
FORCEPROP 1 LAST HDL_POWER PVNN_PCH_STBY
J 1
(1350 3800);
DISPLAY 0.872340 (1350 3800);
PAINT GREEN (1350 3800);
DISPLAY INVISIBLE (1350 3800);
FORCEADD GND..1
(2075 3175);
FORCEPROP 3 LASTPIN (2075 3225) SIG_NAME GND\g
J 0
(2085 3235);
DISPLAY 0.659574 (2085 3235);
PAINT MONO (2085 3235);
DISPLAY INVISIBLE (2085 3235);
FORCEPROP 1 LAST VOLTAGE 0
J 0
(2075 3175);
PAINT SKYBLUE (2075 3175);
DISPLAY INVISIBLE (2075 3175);
FORCEPROP 2 LAST CDS_LIB mstr_symbols
J 0
(2075 3175);
PAINT ORANGE (2075 3175);
DISPLAY INVISIBLE (2075 3175);
FORCEPROP 1 LAST SIZE 1B
J 0
(2150 3125);
DISPLAY 1.404255 (2150 3125);
PAINT GREEN (2150 3125);
DISPLAY INVISIBLE (2150 3125);
FORCEPROP 2 LAST BOM_COST SB
J 0
(2025 3250);
PAINT MONO (2025 3250);
DISPLAY INVISIBLE (2025 3250);
FORCEPROP 1 LAST BODY_TYPE PLUMBING
J 0
(2030 3132);
DISPLAY 0.340426 (2030 3132);
PAINT GREEN (2030 3132);
DISPLAY INVISIBLE (2030 3132);
FORCEPROP 1 LAST PATH I15
J 0
(2150 3175);
DISPLAY 0.872340 (2150 3175);
PAINT AQUA (2150 3175);
DISPLAY INVISIBLE (2150 3175);
FORCEPROP 2 LAST ROOM SB_DECOUPLING
J 0
(1600 3250);
PAINT WHITE (1600 3250);
DISPLAY INVISIBLE (1600 3250);
FORCEPROP 1 LAST HDL_POWER GND
J 0
(2075 3325);
DISPLAY 1.404255 (2075 3325);
PAINT GREEN (2075 3325);
DISPLAY INVISIBLE (2075 3325);
FORCEADD CAP_A..1
(1850 2525);
FORCEPROP 1 LAST LOCATION C3N24
J 0
(1900 2625);
DISPLAY 0.617021 (1900 2625);
PAINT AQUA (1900 2625);
FORCEPROP 1 LAST PART_NUMBER E15431-004
J 0
(1900 2375);
DISPLAY 0.617021 (1900 2375);
PAINT BLUE (1900 2375);
FORCEPROP 1 LAST VALUE 22.0UF
J 0
(1900 2575);
DISPLAY 0.617021 (1900 2575);
PAINT SKYBLUE (1900 2575);
FORCEPROP 1 LAST TOLERANCE 20%
J 0
(1900 2475);
DISPLAY 0.617021 (1900 2475);
PAINT SKYBLUE (1900 2475);
FORCEPROP 1 LAST PACK_TYPE 0603V
J 0
(1900 2325);
DISPLAY 0.617021 (1900 2325);
PAINT SKYBLUE (1900 2325);
FORCEPROP 1 LAST VOLTAGE 4V
J 0
(1900 2525);
DISPLAY 0.617021 (1900 2525);
PAINT SKYBLUE (1900 2525);
FORCEPROP 1 LAST MATERIAL X6S
J 0
(1900 2425);
DISPLAY 0.617021 (1900 2425);
PAINT SKYBLUE (1900 2425);
FORCEPROP 2 LAST CDS_LOCATION C3N24
J 0
(1900 2625);
DISPLAY 0.617021 (1900 2625);
PAINT AQUA (1900 2625);
DISPLAY INVISIBLE (1900 2625);
FORCEPROP 2 LAST BOM_COST SB
J 0
(1900 2275);
PAINT MONO (1900 2275);
DISPLAY INVISIBLE (1900 2275);
FORCEPROP 2 LAST CDS_LIB dev_discrete
J 0
(1850 2525);
PAINT ORANGE (1850 2525);
DISPLAY INVISIBLE (1850 2525);
FORCEPROP 2 LAST CDS_SEC 1
J 0
(1900 2725);
DISPLAY 1.361702 (1900 2725);
PAINT ORANGE (1900 2725);
DISPLAY INVISIBLE (1900 2725);
FORCEPROP 2 LAST $SEC 1
J 0
(1900 2725);
DISPLAY 0.914894 (1900 2725);
PAINT MONO (1900 2725);
DISPLAY INVISIBLE (1900 2725);
FORCEPROP 1 LAST PATH I16
J 0
(1900 2675);
DISPLAY 0.978723 (1900 2675);
PAINT WHITE (1900 2675);
DISPLAY INVISIBLE (1900 2675);
FORCEPROP 2 LAST ROOM SB_DECOUPLING
J 0
(1850 2525);
PAINT WHITE (1850 2525);
DISPLAY INVISIBLE (1850 2525);
FORCEPROP 1 LASTPIN (1850 2625) $PN 1
J 0
(1860 2605);
DISPLAY 1.063830 (1860 2605);
PAINT WHITE (1860 2605);
DISPLAY INVISIBLE (1860 2605);
FORCEPROP 1 LASTPIN (1850 2425) $PN 2
J 0
(1860 2405);
DISPLAY 1.063830 (1860 2405);
PAINT WHITE (1860 2405);
DISPLAY INVISIBLE (1860 2405);
FORCEADD CAP_A..1
(1475 2525);
FORCEPROP 1 LAST LOCATION C3N28
J 0
(1525 2625);
DISPLAY 0.617021 (1525 2625);
PAINT AQUA (1525 2625);
FORCEPROP 1 LAST PART_NUMBER E15431-004
J 0
(1525 2375);
DISPLAY 0.617021 (1525 2375);
PAINT BLUE (1525 2375);
FORCEPROP 1 LAST VALUE 22.0UF
J 0
(1525 2575);
DISPLAY 0.617021 (1525 2575);
PAINT SKYBLUE (1525 2575);
FORCEPROP 1 LAST TOLERANCE 20%
J 0
(1525 2475);
DISPLAY 0.617021 (1525 2475);
PAINT SKYBLUE (1525 2475);
FORCEPROP 1 LAST PACK_TYPE 0603V
J 0
(1525 2325);
DISPLAY 0.617021 (1525 2325);
PAINT SKYBLUE (1525 2325);
FORCEPROP 1 LAST VOLTAGE 4V
J 0
(1525 2525);
DISPLAY 0.617021 (1525 2525);
PAINT SKYBLUE (1525 2525);
FORCEPROP 1 LAST MATERIAL X6S
J 0
(1525 2425);
DISPLAY 0.617021 (1525 2425);
PAINT SKYBLUE (1525 2425);
FORCEPROP 2 LAST CDS_LOCATION C3N28
J 0
(1525 2625);
DISPLAY 0.617021 (1525 2625);
PAINT AQUA (1525 2625);
DISPLAY INVISIBLE (1525 2625);
FORCEPROP 2 LAST BOM_COST SB
J 0
(1525 2275);
PAINT MONO (1525 2275);
DISPLAY INVISIBLE (1525 2275);
FORCEPROP 2 LAST CDS_LIB dev_discrete
J 0
(1475 2525);
PAINT ORANGE (1475 2525);
DISPLAY INVISIBLE (1475 2525);
FORCEPROP 2 LAST CDS_SEC 1
J 0
(1525 2725);
DISPLAY 1.361702 (1525 2725);
PAINT ORANGE (1525 2725);
DISPLAY INVISIBLE (1525 2725);
FORCEPROP 2 LAST $SEC 1
J 0
(1525 2725);
DISPLAY 0.914894 (1525 2725);
PAINT MONO (1525 2725);
DISPLAY INVISIBLE (1525 2725);
FORCEPROP 1 LAST PATH I17
J 0
(1525 2675);
DISPLAY 0.978723 (1525 2675);
PAINT WHITE (1525 2675);
DISPLAY INVISIBLE (1525 2675);
FORCEPROP 2 LAST ROOM SB_DECOUPLING
J 0
(1475 2525);
PAINT WHITE (1475 2525);
DISPLAY INVISIBLE (1475 2525);
FORCEPROP 1 LASTPIN (1475 2625) $PN 1
J 0
(1485 2605);
DISPLAY 1.063830 (1485 2605);
PAINT WHITE (1485 2605);
DISPLAY INVISIBLE (1485 2605);
FORCEPROP 1 LASTPIN (1475 2425) $PN 2
J 0
(1485 2405);
DISPLAY 1.063830 (1485 2405);
PAINT WHITE (1485 2405);
DISPLAY INVISIBLE (1485 2405);
FORCEADD PVNN_PCH_STBY..1
(1400 2775);
FORCEPROP 3 LASTPIN (1400 2725) SIG_NAME PVNN_PCH_STBY\g
J 0
(1410 2735);
DISPLAY 0.659574 (1410 2735);
PAINT MONO (1410 2735);
DISPLAY INVISIBLE (1410 2735);
FORCEPROP 1 LAST VOLTAGE 1.0V
J 0
(1355 2732);
DISPLAY 0.340426 (1355 2732);
PAINT SKYBLUE (1355 2732);
DISPLAY INVISIBLE (1355 2732);
FORCEPROP 2 LAST CDS_LIB mstr_symbols
J 0
(1400 2775);
PAINT ORANGE (1400 2775);
DISPLAY INVISIBLE (1400 2775);
FORCEPROP 2 LAST BOM_COST SB
J 0
(1400 2875);
DISPLAY 1.361702 (1400 2875);
PAINT ORANGE (1400 2875);
DISPLAY INVISIBLE (1400 2875);
FORCEPROP 1 LAST BODY_TYPE PLUMBING
J 0
(1355 2732);
DISPLAY 0.340426 (1355 2732);
PAINT GREEN (1355 2732);
DISPLAY INVISIBLE (1355 2732);
FORCEPROP 1 LAST PATH I18
J 0
(1450 2800);
DISPLAY 0.872340 (1450 2800);
PAINT AQUA (1450 2800);
DISPLAY INVISIBLE (1450 2800);
FORCEPROP 2 LAST ROOM SB_DECOUPLING
J 0
(1400 2875);
DISPLAY 1.361702 (1400 2875);
PAINT WHITE (1400 2875);
DISPLAY INVISIBLE (1400 2875);
FORCEPROP 1 LAST HDL_POWER PVNN_PCH_STBY
J 1
(1400 2825);
DISPLAY 0.872340 (1400 2825);
PAINT GREEN (1400 2825);
DISPLAY INVISIBLE (1400 2825);
FORCEADD CAP_A..1
(1075 3500);
FORCEPROP 1 LAST LOCATION C3N11
J 0
(1125 3600);
DISPLAY 0.617021 (1125 3600);
PAINT AQUA (1125 3600);
FORCEPROP 1 LAST PART_NUMBER E15431-004
J 0
(1125 3350);
DISPLAY 0.617021 (1125 3350);
PAINT BLUE (1125 3350);
FORCEPROP 1 LAST VALUE 22.0UF
J 0
(1125 3550);
DISPLAY 0.617021 (1125 3550);
PAINT SKYBLUE (1125 3550);
FORCEPROP 1 LAST TOLERANCE 20%
J 0
(1125 3450);
DISPLAY 0.617021 (1125 3450);
PAINT SKYBLUE (1125 3450);
FORCEPROP 1 LAST PACK_TYPE 0603V
J 0
(1125 3300);
DISPLAY 0.617021 (1125 3300);
PAINT SKYBLUE (1125 3300);
FORCEPROP 1 LAST VOLTAGE 4V
J 0
(1125 3500);
DISPLAY 0.617021 (1125 3500);
PAINT SKYBLUE (1125 3500);
FORCEPROP 1 LAST MATERIAL X6S
J 0
(1125 3400);
DISPLAY 0.617021 (1125 3400);
PAINT SKYBLUE (1125 3400);
FORCEPROP 2 LAST CDS_LOCATION C3N11
J 0
(1125 3600);
DISPLAY 0.617021 (1125 3600);
PAINT AQUA (1125 3600);
DISPLAY INVISIBLE (1125 3600);
FORCEPROP 2 LAST BOM_COST SB
J 0
(1125 3250);
PAINT MONO (1125 3250);
DISPLAY INVISIBLE (1125 3250);
FORCEPROP 2 LAST CDS_LIB dev_discrete
J 0
(1075 3500);
PAINT ORANGE (1075 3500);
DISPLAY INVISIBLE (1075 3500);
FORCEPROP 2 LAST CDS_SEC 1
J 0
(1125 3700);
DISPLAY 1.361702 (1125 3700);
PAINT ORANGE (1125 3700);
DISPLAY INVISIBLE (1125 3700);
FORCEPROP 2 LAST $SEC 1
J 0
(1125 3700);
DISPLAY 0.914894 (1125 3700);
PAINT MONO (1125 3700);
DISPLAY INVISIBLE (1125 3700);
FORCEPROP 1 LAST PATH I19
J 0
(1125 3650);
DISPLAY 0.978723 (1125 3650);
PAINT WHITE (1125 3650);
DISPLAY INVISIBLE (1125 3650);
FORCEPROP 2 LAST ROOM SB_DECOUPLING
J 0
(1075 3500);
PAINT WHITE (1075 3500);
DISPLAY INVISIBLE (1075 3500);
FORCEPROP 1 LASTPIN (1075 3600) $PN 1
J 0
(1085 3580);
DISPLAY 1.063830 (1085 3580);
PAINT WHITE (1085 3580);
DISPLAY INVISIBLE (1085 3580);
FORCEPROP 1 LASTPIN (1075 3400) $PN 2
J 0
(1085 3380);
DISPLAY 1.063830 (1085 3380);
PAINT WHITE (1085 3380);
DISPLAY INVISIBLE (1085 3380);
FORCEADD CAP_A..1
(2200 4475);
FORCEPROP 1 LAST LOCATION C3M7
J 0
(2250 4575);
DISPLAY 0.617021 (2250 4575);
PAINT AQUA (2250 4575);
FORCEPROP 1 LAST PART_NUMBER E15431-004
J 0
(2250 4325);
DISPLAY 0.617021 (2250 4325);
PAINT BLUE (2250 4325);
FORCEPROP 1 LAST VALUE 22.0UF
J 0
(2250 4525);
DISPLAY 0.617021 (2250 4525);
PAINT SKYBLUE (2250 4525);
FORCEPROP 1 LAST TOLERANCE 20%
J 0
(2250 4425);
DISPLAY 0.617021 (2250 4425);
PAINT SKYBLUE (2250 4425);
FORCEPROP 1 LAST PACK_TYPE 0603V
J 0
(2250 4275);
DISPLAY 0.617021 (2250 4275);
PAINT SKYBLUE (2250 4275);
FORCEPROP 1 LAST VOLTAGE 4V
J 0
(2250 4475);
DISPLAY 0.617021 (2250 4475);
PAINT SKYBLUE (2250 4475);
FORCEPROP 1 LAST MATERIAL X6S
J 0
(2250 4375);
DISPLAY 0.617021 (2250 4375);
PAINT SKYBLUE (2250 4375);
FORCEPROP 1 LASTPIN (2200 4575) $PN 1
J 0
(2210 4555);
DISPLAY 0.617021 (2210 4555);
PAINT WHITE (2210 4555);
FORCEPROP 1 LASTPIN (2200 4375) $PN 2
J 0
(2210 4355);
DISPLAY 0.617021 (2210 4355);
PAINT WHITE (2210 4355);
FORCEPROP 2 LAST CDS_LOCATION C3M7
J 0
(2250 4575);
DISPLAY 0.617021 (2250 4575);
PAINT AQUA (2250 4575);
DISPLAY INVISIBLE (2250 4575);
FORCEPROP 2 LAST BOM_COST SB
J 0
(2250 4675);
DISPLAY 1.361702 (2250 4675);
PAINT ORANGE (2250 4675);
DISPLAY INVISIBLE (2250 4675);
FORCEPROP 2 LAST CDS_LIB dev_discrete
J 0
(2200 4475);
PAINT ORANGE (2200 4475);
DISPLAY INVISIBLE (2200 4475);
FORCEPROP 2 LAST CDS_SEC 1
J 0
(2250 4675);
DISPLAY 1.361702 (2250 4675);
PAINT ORANGE (2250 4675);
DISPLAY INVISIBLE (2250 4675);
FORCEPROP 2 LAST $SEC 1
J 0
(2250 4675);
DISPLAY 0.914894 (2250 4675);
PAINT MONO (2250 4675);
DISPLAY INVISIBLE (2250 4675);
FORCEPROP 1 LAST PATH I2
J 0
(2250 4625);
DISPLAY 0.978723 (2250 4625);
PAINT WHITE (2250 4625);
DISPLAY INVISIBLE (2250 4625);
FORCEPROP 2 LAST ROOM SB_DECOUPLING
J 0
(2250 4625);
DISPLAY 1.361702 (2250 4625);
PAINT ORANGE (2250 4625);
DISPLAY INVISIBLE (2250 4625);
FORCEADD CAP_A..1
(1100 2525);
FORCEPROP 1 LAST LOCATION C3N31
J 0
(1150 2625);
DISPLAY 0.617021 (1150 2625);
PAINT AQUA (1150 2625);
FORCEPROP 1 LAST PART_NUMBER E15431-004
J 0
(1150 2375);
DISPLAY 0.617021 (1150 2375);
PAINT BLUE (1150 2375);
FORCEPROP 1 LAST VALUE 22.0UF
J 0
(1150 2575);
DISPLAY 0.617021 (1150 2575);
PAINT SKYBLUE (1150 2575);
FORCEPROP 1 LAST TOLERANCE 20%
J 0
(1150 2475);
DISPLAY 0.617021 (1150 2475);
PAINT SKYBLUE (1150 2475);
FORCEPROP 1 LAST PACK_TYPE 0603V
J 0
(1150 2325);
DISPLAY 0.617021 (1150 2325);
PAINT SKYBLUE (1150 2325);
FORCEPROP 1 LAST VOLTAGE 4V
J 0
(1150 2525);
DISPLAY 0.617021 (1150 2525);
PAINT SKYBLUE (1150 2525);
FORCEPROP 1 LAST MATERIAL X6S
J 0
(1150 2425);
DISPLAY 0.617021 (1150 2425);
PAINT SKYBLUE (1150 2425);
FORCEPROP 2 LAST CDS_LOCATION C3N31
J 0
(1150 2625);
DISPLAY 0.617021 (1150 2625);
PAINT AQUA (1150 2625);
DISPLAY INVISIBLE (1150 2625);
FORCEPROP 2 LAST BOM_COST SB
J 0
(1150 2275);
PAINT MONO (1150 2275);
DISPLAY INVISIBLE (1150 2275);
FORCEPROP 2 LAST CDS_LIB dev_discrete
J 0
(1100 2525);
PAINT ORANGE (1100 2525);
DISPLAY INVISIBLE (1100 2525);
FORCEPROP 2 LAST CDS_SEC 1
J 0
(1150 2725);
DISPLAY 1.361702 (1150 2725);
PAINT ORANGE (1150 2725);
DISPLAY INVISIBLE (1150 2725);
FORCEPROP 2 LAST $SEC 1
J 0
(1150 2725);
DISPLAY 0.914894 (1150 2725);
PAINT MONO (1150 2725);
DISPLAY INVISIBLE (1150 2725);
FORCEPROP 1 LAST PATH I20
J 0
(1150 2675);
DISPLAY 0.978723 (1150 2675);
PAINT WHITE (1150 2675);
DISPLAY INVISIBLE (1150 2675);
FORCEPROP 2 LAST ROOM SB_DECOUPLING
J 0
(1100 2525);
PAINT WHITE (1100 2525);
DISPLAY INVISIBLE (1100 2525);
FORCEPROP 1 LASTPIN (1100 2625) $PN 1
J 0
(1110 2605);
DISPLAY 1.063830 (1110 2605);
PAINT WHITE (1110 2605);
DISPLAY INVISIBLE (1110 2605);
FORCEPROP 1 LASTPIN (1100 2425) $PN 2
J 0
(1110 2405);
DISPLAY 1.063830 (1110 2405);
PAINT WHITE (1110 2405);
DISPLAY INVISIBLE (1110 2405);
FORCEADD GND..1
(2050 2200);
FORCEPROP 3 LASTPIN (2050 2250) SIG_NAME GND\g
J 0
(2060 2260);
DISPLAY 0.659574 (2060 2260);
PAINT MONO (2060 2260);
DISPLAY INVISIBLE (2060 2260);
FORCEPROP 1 LAST VOLTAGE 0
J 0
(2050 2200);
PAINT SKYBLUE (2050 2200);
DISPLAY INVISIBLE (2050 2200);
FORCEPROP 2 LAST BOM_COST SB
J 0
(2000 2275);
PAINT MONO (2000 2275);
DISPLAY INVISIBLE (2000 2275);
FORCEPROP 2 LAST CDS_LIB mstr_symbols
J 0
(2050 2200);
PAINT ORANGE (2050 2200);
DISPLAY INVISIBLE (2050 2200);
FORCEPROP 1 LAST SIZE 1B
J 0
(2125 2150);
DISPLAY 1.404255 (2125 2150);
PAINT GREEN (2125 2150);
DISPLAY INVISIBLE (2125 2150);
FORCEPROP 1 LAST BODY_TYPE PLUMBING
J 0
(2005 2157);
DISPLAY 0.340426 (2005 2157);
PAINT GREEN (2005 2157);
DISPLAY INVISIBLE (2005 2157);
FORCEPROP 1 LAST PATH I21
J 0
(2125 2200);
DISPLAY 0.872340 (2125 2200);
PAINT AQUA (2125 2200);
DISPLAY INVISIBLE (2125 2200);
FORCEPROP 2 LAST ROOM SB_DECOUPLING
J 0
(1575 2275);
PAINT WHITE (1575 2275);
DISPLAY INVISIBLE (1575 2275);
FORCEPROP 1 LAST HDL_POWER GND
J 0
(2050 2350);
DISPLAY 1.404255 (2050 2350);
PAINT GREEN (2050 2350);
DISPLAY INVISIBLE (2050 2350);
FORCEADD PVNN_PCH_STBY..1
(1925 1875);
FORCEPROP 3 LASTPIN (1925 1825) SIG_NAME PVNN_PCH_STBY\g
J 0
(1935 1835);
DISPLAY 0.659574 (1935 1835);
PAINT MONO (1935 1835);
DISPLAY INVISIBLE (1935 1835);
FORCEPROP 1 LAST VOLTAGE 1.0V
J 0
(1880 1832);
DISPLAY 0.340426 (1880 1832);
PAINT SKYBLUE (1880 1832);
DISPLAY INVISIBLE (1880 1832);
FORCEPROP 2 LAST CDS_LIB mstr_symbols
J 0
(1925 1875);
PAINT ORANGE (1925 1875);
DISPLAY INVISIBLE (1925 1875);
FORCEPROP 2 LAST BOM_COST SB
J 0
(1925 1975);
DISPLAY 1.361702 (1925 1975);
PAINT ORANGE (1925 1975);
DISPLAY INVISIBLE (1925 1975);
FORCEPROP 1 LAST BODY_TYPE PLUMBING
J 0
(1880 1832);
DISPLAY 0.340426 (1880 1832);
PAINT GREEN (1880 1832);
DISPLAY INVISIBLE (1880 1832);
FORCEPROP 1 LAST PATH I22
J 0
(1975 1900);
DISPLAY 0.872340 (1975 1900);
PAINT AQUA (1975 1900);
DISPLAY INVISIBLE (1975 1900);
FORCEPROP 2 LAST ROOM SB_DECOUPLING
J 0
(1925 1975);
DISPLAY 1.361702 (1925 1975);
PAINT ORANGE (1925 1975);
DISPLAY INVISIBLE (1925 1975);
FORCEPROP 1 LAST HDL_POWER PVNN_PCH_STBY
J 1
(1925 1925);
DISPLAY 0.872340 (1925 1925);
PAINT GREEN (1925 1925);
DISPLAY INVISIBLE (1925 1925);
FORCEADD CAP..1
(2150 1575);
FORCEPROP 1 LAST LOCATION C7A33
J 0
(2200 1675);
DISPLAY 0.617021 (2200 1675);
PAINT AQUA (2200 1675);
FORCEPROP 1 LAST PART_NUMBER C95333-006
J 0
(2200 1425);
DISPLAY 0.617021 (2200 1425);
PAINT BLUE (2200 1425);
FORCEPROP 1 LAST VALUE 47UF
J 0
(2200 1625);
DISPLAY 0.617021 (2200 1625);
PAINT SKYBLUE (2200 1625);
FORCEPROP 1 LAST TOLERANCE 20%
J 0
(2200 1525);
DISPLAY 0.617021 (2200 1525);
PAINT SKYBLUE (2200 1525);
FORCEPROP 1 LAST PACK_TYPE 0805
J 0
(2200 1375);
DISPLAY 0.617021 (2200 1375);
PAINT SKYBLUE (2200 1375);
FORCEPROP 1 LAST VOLTAGE 4V
J 0
(2200 1575);
DISPLAY 0.617021 (2200 1575);
PAINT SKYBLUE (2200 1575);
FORCEPROP 1 LAST MATERIAL X6S
J 0
(2200 1475);
DISPLAY 0.617021 (2200 1475);
PAINT SKYBLUE (2200 1475);
FORCEPROP 1 LASTPIN (2150 1475) $PN 2
J 0
(2160 1455);
DISPLAY 0.617021 (2160 1455);
PAINT WHITE (2160 1455);
FORCEPROP 1 LASTPIN (2150 1675) $PN 1
J 0
(2160 1655);
DISPLAY 0.617021 (2160 1655);
PAINT WHITE (2160 1655);
FORCEPROP 2 LAST CDS_LIB mstr_discrete
J 0
(2150 1575);
PAINT MONO (2150 1575);
DISPLAY INVISIBLE (2150 1575);
FORCEPROP 2 LAST BOM_COST SB
J 0
(2200 1775);
DISPLAY 1.361702 (2200 1775);
PAINT ORANGE (2200 1775);
DISPLAY INVISIBLE (2200 1775);
FORCEPROP 2 LAST CDS_SEC 1
J 0
(2200 1775);
DISPLAY 1.361702 (2200 1775);
PAINT ORANGE (2200 1775);
DISPLAY INVISIBLE (2200 1775);
FORCEPROP 2 LAST $SEC 1
J 0
(2200 1775);
DISPLAY 0.914894 (2200 1775);
PAINT MONO (2200 1775);
DISPLAY INVISIBLE (2200 1775);
FORCEPROP 2 LAST CDS_LOCATION C7A33
J 0
(2200 1675);
DISPLAY 0.617021 (2200 1675);
PAINT AQUA (2200 1675);
DISPLAY INVISIBLE (2200 1675);
FORCEPROP 1 LAST PATH I23
J 0
(2200 1725);
DISPLAY 0.978723 (2200 1725);
PAINT WHITE (2200 1725);
DISPLAY INVISIBLE (2200 1725);
FORCEPROP 2 LAST ROOM SB_DECOUPLING
J 0
(2200 1725);
DISPLAY 1.361702 (2200 1725);
PAINT ORANGE (2200 1725);
DISPLAY INVISIBLE (2200 1725);
FORCEADD CAP..1
(1700 1575);
FORCEPROP 1 LAST LOCATION C7B4
J 0
(1750 1675);
DISPLAY 0.617021 (1750 1675);
PAINT AQUA (1750 1675);
FORCEPROP 1 LAST PART_NUMBER C95333-006
J 0
(1750 1425);
DISPLAY 0.617021 (1750 1425);
PAINT BLUE (1750 1425);
FORCEPROP 1 LAST VALUE 47UF
J 0
(1750 1625);
DISPLAY 0.617021 (1750 1625);
PAINT SKYBLUE (1750 1625);
FORCEPROP 1 LAST TOLERANCE 20%
J 0
(1750 1525);
DISPLAY 0.617021 (1750 1525);
PAINT SKYBLUE (1750 1525);
FORCEPROP 1 LAST PACK_TYPE 0805
J 0
(1750 1375);
DISPLAY 0.617021 (1750 1375);
PAINT SKYBLUE (1750 1375);
FORCEPROP 1 LAST VOLTAGE 4V
J 0
(1750 1575);
DISPLAY 0.617021 (1750 1575);
PAINT SKYBLUE (1750 1575);
FORCEPROP 1 LAST MATERIAL X6S
J 0
(1750 1475);
DISPLAY 0.617021 (1750 1475);
PAINT SKYBLUE (1750 1475);
FORCEPROP 1 LASTPIN (1700 1475) $PN 2
J 0
(1710 1455);
DISPLAY 0.617021 (1710 1455);
PAINT WHITE (1710 1455);
FORCEPROP 1 LASTPIN (1700 1675) $PN 1
J 0
(1710 1655);
DISPLAY 0.617021 (1710 1655);
PAINT WHITE (1710 1655);
FORCEPROP 2 LAST CDS_LIB mstr_discrete
J 0
(1700 1575);
PAINT MONO (1700 1575);
DISPLAY INVISIBLE (1700 1575);
FORCEPROP 2 LAST BOM_COST SB
J 0
(1750 1775);
DISPLAY 1.361702 (1750 1775);
PAINT ORANGE (1750 1775);
DISPLAY INVISIBLE (1750 1775);
FORCEPROP 2 LAST CDS_SEC 1
J 0
(1750 1775);
DISPLAY 1.361702 (1750 1775);
PAINT ORANGE (1750 1775);
DISPLAY INVISIBLE (1750 1775);
FORCEPROP 2 LAST $SEC 1
J 0
(1750 1775);
DISPLAY 0.914894 (1750 1775);
PAINT MONO (1750 1775);
DISPLAY INVISIBLE (1750 1775);
FORCEPROP 2 LAST CDS_LOCATION C7B4
J 0
(1750 1675);
DISPLAY 0.617021 (1750 1675);
PAINT AQUA (1750 1675);
DISPLAY INVISIBLE (1750 1675);
FORCEPROP 1 LAST PATH I24
J 0
(1750 1725);
DISPLAY 0.978723 (1750 1725);
PAINT WHITE (1750 1725);
DISPLAY INVISIBLE (1750 1725);
FORCEPROP 2 LAST ROOM SB_DECOUPLING
J 0
(1750 1725);
DISPLAY 1.361702 (1750 1725);
PAINT ORANGE (1750 1725);
DISPLAY INVISIBLE (1750 1725);
FORCEADD GND..1
(1925 1200);
FORCEPROP 3 LASTPIN (1925 1250) SIG_NAME GND\g
J 0
(1935 1260);
DISPLAY 0.659574 (1935 1260);
PAINT MONO (1935 1260);
DISPLAY INVISIBLE (1935 1260);
FORCEPROP 1 LAST VOLTAGE 0.0V
J 0
(1880 1157);
DISPLAY 0.340426 (1880 1157);
PAINT SKYBLUE (1880 1157);
DISPLAY INVISIBLE (1880 1157);
FORCEPROP 2 LAST BOM_COST SB
J 0
(1950 1275);
DISPLAY 1.361702 (1950 1275);
PAINT ORANGE (1950 1275);
DISPLAY INVISIBLE (1950 1275);
FORCEPROP 2 LAST CDS_LIB mstr_symbols
J 0
(1925 1200);
PAINT MONO (1925 1200);
DISPLAY INVISIBLE (1925 1200);
FORCEPROP 1 LAST SIZE 1B
J 0
(2000 1150);
DISPLAY 1.170213 (2000 1150);
PAINT AQUA (2000 1150);
DISPLAY INVISIBLE (2000 1150);
FORCEPROP 1 LAST BODY_TYPE PLUMBING
J 0
(1880 1157);
DISPLAY 0.340426 (1880 1157);
PAINT GREEN (1880 1157);
DISPLAY INVISIBLE (1880 1157);
FORCEPROP 1 LAST PATH I25
J 0
(2000 1200);
DISPLAY 0.872340 (2000 1200);
PAINT AQUA (2000 1200);
DISPLAY INVISIBLE (2000 1200);
FORCEPROP 2 LAST ROOM SB_DECOUPLING
J 0
(1950 1275);
DISPLAY 1.361702 (1950 1275);
PAINT ORANGE (1950 1275);
DISPLAY INVISIBLE (1950 1275);
FORCEPROP 1 LAST HDL_POWER GND
J 0
(1925 1350);
DISPLAY 1.170213 (1925 1350);
PAINT GREEN (1925 1350);
DISPLAY INVISIBLE (1925 1350);
FORCEADD CAP_A..1
(-325 4050);
FORCEPROP 1 LAST LOCATION C2N9
J 0
(-275 4150);
DISPLAY 0.617021 (-275 4150);
PAINT AQUA (-275 4150);
FORCEPROP 1 LAST PART_NUMBER D97712-004
J 0
(-275 3900);
DISPLAY 0.617021 (-275 3900);
PAINT BLUE (-275 3900);
FORCEPROP 1 LAST VALUE 1.0UF
J 0
(-275 4100);
DISPLAY 0.617021 (-275 4100);
PAINT SKYBLUE (-275 4100);
FORCEPROP 1 LAST TOLERANCE 10%
J 0
(-275 4000);
DISPLAY 0.617021 (-275 4000);
PAINT SKYBLUE (-275 4000);
FORCEPROP 1 LAST PACK_TYPE 0402V
J 0
(-275 3850);
DISPLAY 0.617021 (-275 3850);
PAINT SKYBLUE (-275 3850);
FORCEPROP 1 LAST VOLTAGE 6.3V
J 0
(-275 4050);
DISPLAY 0.617021 (-275 4050);
PAINT SKYBLUE (-275 4050);
FORCEPROP 1 LAST MATERIAL X6S
J 0
(-275 3950);
DISPLAY 0.617021 (-275 3950);
PAINT SKYBLUE (-275 3950);
FORCEPROP 1 LASTPIN (-325 4150) $PN 1
J 0
(-315 4130);
DISPLAY 0.617021 (-315 4130);
PAINT WHITE (-315 4130);
FORCEPROP 1 LASTPIN (-325 3950) $PN 2
J 0
(-315 3930);
DISPLAY 0.617021 (-315 3930);
PAINT WHITE (-315 3930);
FORCEPROP 2 LAST CDS_LOCATION C2N9
J 0
(-275 4150);
DISPLAY 0.617021 (-275 4150);
PAINT AQUA (-275 4150);
DISPLAY INVISIBLE (-275 4150);
FORCEPROP 2 LAST CDS_LIB dev_discrete
J 0
(-325 4050);
PAINT ORANGE (-325 4050);
DISPLAY INVISIBLE (-325 4050);
FORCEPROP 2 LAST CDS_SEC 1
J 0
(-275 4250);
PAINT MONO (-275 4250);
DISPLAY INVISIBLE (-275 4250);
FORCEPROP 2 LAST $SEC 1
J 0
(-275 4250);
DISPLAY 0.914894 (-275 4250);
PAINT MONO (-275 4250);
DISPLAY INVISIBLE (-275 4250);
FORCEPROP 1 LAST PATH I26
J 0
(-275 4200);
DISPLAY 0.978723 (-275 4200);
PAINT WHITE (-275 4200);
DISPLAY INVISIBLE (-275 4200);
FORCEPROP 2 LAST ROOM SB_DECOUPLING
J 0
(-275 4200);
DISPLAY 1.361702 (-275 4200);
PAINT ORANGE (-275 4200);
DISPLAY INVISIBLE (-275 4200);
FORCEADD CAP_A..1
(-725 4050);
FORCEPROP 1 LAST LOCATION C2N3
J 0
(-675 4150);
DISPLAY 0.617021 (-675 4150);
PAINT AQUA (-675 4150);
FORCEPROP 1 LAST PART_NUMBER D97712-004
J 0
(-675 3900);
DISPLAY 0.617021 (-675 3900);
PAINT BLUE (-675 3900);
FORCEPROP 1 LAST VALUE 1.0UF
J 0
(-675 4100);
DISPLAY 0.617021 (-675 4100);
PAINT SKYBLUE (-675 4100);
FORCEPROP 1 LAST TOLERANCE 10%
J 0
(-675 4000);
DISPLAY 0.617021 (-675 4000);
PAINT SKYBLUE (-675 4000);
FORCEPROP 1 LAST PACK_TYPE 0402V
J 0
(-675 3850);
DISPLAY 0.617021 (-675 3850);
PAINT SKYBLUE (-675 3850);
FORCEPROP 1 LAST VOLTAGE 6.3V
J 0
(-675 4050);
DISPLAY 0.617021 (-675 4050);
PAINT SKYBLUE (-675 4050);
FORCEPROP 1 LAST MATERIAL X6S
J 0
(-675 3950);
DISPLAY 0.617021 (-675 3950);
PAINT SKYBLUE (-675 3950);
FORCEPROP 1 LASTPIN (-725 4150) $PN 1
J 0
(-715 4130);
DISPLAY 0.617021 (-715 4130);
PAINT WHITE (-715 4130);
FORCEPROP 1 LASTPIN (-725 3950) $PN 2
J 0
(-715 3930);
DISPLAY 0.617021 (-715 3930);
PAINT WHITE (-715 3930);
FORCEPROP 2 LAST CDS_LOCATION C2N3
J 0
(-675 4150);
DISPLAY 0.617021 (-675 4150);
PAINT AQUA (-675 4150);
DISPLAY INVISIBLE (-675 4150);
FORCEPROP 2 LAST BOM_COST SB
J 0
(-675 3800);
PAINT MONO (-675 3800);
DISPLAY INVISIBLE (-675 3800);
FORCEPROP 2 LAST CDS_LIB dev_discrete
J 0
(-725 4050);
PAINT ORANGE (-725 4050);
DISPLAY INVISIBLE (-725 4050);
FORCEPROP 2 LAST CDS_SEC 1
J 0
(-675 4250);
DISPLAY 1.361702 (-675 4250);
PAINT ORANGE (-675 4250);
DISPLAY INVISIBLE (-675 4250);
FORCEPROP 2 LAST $SEC 1
J 0
(-675 4250);
DISPLAY 0.914894 (-675 4250);
PAINT MONO (-675 4250);
DISPLAY INVISIBLE (-675 4250);
FORCEPROP 1 LAST PATH I27
J 0
(-675 4200);
DISPLAY 0.978723 (-675 4200);
PAINT WHITE (-675 4200);
DISPLAY INVISIBLE (-675 4200);
FORCEPROP 2 LAST ROOM SB_DECOUPLING
J 0
(-725 4050);
PAINT WHITE (-725 4050);
DISPLAY INVISIBLE (-725 4050);
FORCEADD CAP_A..1
(-300 3025);
FORCEPROP 1 LAST LOCATION C2N4
J 0
(-250 3125);
DISPLAY 0.617021 (-250 3125);
PAINT AQUA (-250 3125);
FORCEPROP 1 LAST PART_NUMBER D97712-004
J 0
(-250 2875);
DISPLAY 0.617021 (-250 2875);
PAINT BLUE (-250 2875);
FORCEPROP 1 LAST VALUE 1.0UF
J 0
(-250 3075);
DISPLAY 0.617021 (-250 3075);
PAINT SKYBLUE (-250 3075);
FORCEPROP 1 LAST TOLERANCE 10%
J 0
(-250 2975);
DISPLAY 0.617021 (-250 2975);
PAINT SKYBLUE (-250 2975);
FORCEPROP 1 LAST PACK_TYPE 0402V
J 0
(-250 2825);
DISPLAY 0.617021 (-250 2825);
PAINT SKYBLUE (-250 2825);
FORCEPROP 1 LAST VOLTAGE 6.3V
J 0
(-250 3025);
DISPLAY 0.617021 (-250 3025);
PAINT SKYBLUE (-250 3025);
FORCEPROP 1 LAST MATERIAL X6S
J 0
(-250 2925);
DISPLAY 0.617021 (-250 2925);
PAINT SKYBLUE (-250 2925);
FORCEPROP 1 LASTPIN (-300 3125) $PN 1
J 0
(-290 3105);
DISPLAY 0.617021 (-290 3105);
PAINT WHITE (-290 3105);
FORCEPROP 1 LASTPIN (-300 2925) $PN 2
J 0
(-290 2905);
DISPLAY 0.617021 (-290 2905);
PAINT WHITE (-290 2905);
FORCEPROP 2 LAST CDS_LOCATION C2N4
J 0
(-250 3125);
DISPLAY 0.617021 (-250 3125);
PAINT AQUA (-250 3125);
DISPLAY INVISIBLE (-250 3125);
FORCEPROP 2 LAST CDS_LIB dev_discrete
J 0
(-300 3025);
PAINT ORANGE (-300 3025);
DISPLAY INVISIBLE (-300 3025);
FORCEPROP 2 LAST CDS_SEC 1
J 0
(-250 3225);
PAINT MONO (-250 3225);
DISPLAY INVISIBLE (-250 3225);
FORCEPROP 2 LAST $SEC 1
J 0
(-250 3225);
DISPLAY 0.914894 (-250 3225);
PAINT MONO (-250 3225);
DISPLAY INVISIBLE (-250 3225);
FORCEPROP 1 LAST PATH I28
J 0
(-250 3175);
DISPLAY 0.978723 (-250 3175);
PAINT WHITE (-250 3175);
DISPLAY INVISIBLE (-250 3175);
FORCEPROP 2 LAST ROOM SB_DECOUPLING
J 0
(-250 3175);
DISPLAY 1.361702 (-250 3175);
PAINT ORANGE (-250 3175);
DISPLAY INVISIBLE (-250 3175);
FORCEADD CAP_A..1
(-700 3025);
FORCEPROP 1 LAST LOCATION C2N12
J 0
(-650 3125);
DISPLAY 0.617021 (-650 3125);
PAINT AQUA (-650 3125);
FORCEPROP 1 LAST PART_NUMBER D97712-004
J 0
(-650 2875);
DISPLAY 0.617021 (-650 2875);
PAINT BLUE (-650 2875);
FORCEPROP 1 LAST VALUE 1.0UF
J 0
(-650 3075);
DISPLAY 0.617021 (-650 3075);
PAINT SKYBLUE (-650 3075);
FORCEPROP 1 LAST TOLERANCE 10%
J 0
(-650 2975);
DISPLAY 0.617021 (-650 2975);
PAINT SKYBLUE (-650 2975);
FORCEPROP 1 LAST PACK_TYPE 0402V
J 0
(-650 2825);
DISPLAY 0.617021 (-650 2825);
PAINT SKYBLUE (-650 2825);
FORCEPROP 1 LAST VOLTAGE 6.3V
J 0
(-650 3025);
DISPLAY 0.617021 (-650 3025);
PAINT SKYBLUE (-650 3025);
FORCEPROP 1 LAST MATERIAL X6S
J 0
(-650 2925);
DISPLAY 0.617021 (-650 2925);
PAINT SKYBLUE (-650 2925);
FORCEPROP 1 LASTPIN (-700 3125) $PN 1
J 0
(-690 3105);
DISPLAY 0.617021 (-690 3105);
PAINT WHITE (-690 3105);
FORCEPROP 1 LASTPIN (-700 2925) $PN 2
J 0
(-690 2905);
DISPLAY 0.617021 (-690 2905);
PAINT WHITE (-690 2905);
FORCEPROP 2 LAST CDS_LOCATION C2N12
J 0
(-650 3125);
DISPLAY 0.617021 (-650 3125);
PAINT AQUA (-650 3125);
DISPLAY INVISIBLE (-650 3125);
FORCEPROP 2 LAST BOM_COST SB
J 0
(-650 2775);
PAINT MONO (-650 2775);
DISPLAY INVISIBLE (-650 2775);
FORCEPROP 2 LAST CDS_LIB dev_discrete
J 0
(-700 3025);
PAINT ORANGE (-700 3025);
DISPLAY INVISIBLE (-700 3025);
FORCEPROP 2 LAST CDS_SEC 1
J 0
(-650 3225);
DISPLAY 1.361702 (-650 3225);
PAINT ORANGE (-650 3225);
DISPLAY INVISIBLE (-650 3225);
FORCEPROP 2 LAST $SEC 1
J 0
(-650 3225);
DISPLAY 0.914894 (-650 3225);
PAINT MONO (-650 3225);
DISPLAY INVISIBLE (-650 3225);
FORCEPROP 1 LAST PATH I29
J 0
(-650 3175);
DISPLAY 0.978723 (-650 3175);
PAINT WHITE (-650 3175);
DISPLAY INVISIBLE (-650 3175);
FORCEPROP 2 LAST ROOM SB_DECOUPLING
J 0
(-700 3025);
PAINT WHITE (-700 3025);
DISPLAY INVISIBLE (-700 3025);
FORCEADD CAP_A..1
(1825 4475);
FORCEPROP 1 LAST LOCATION C3L26
J 0
(1875 4575);
DISPLAY 0.617021 (1875 4575);
PAINT AQUA (1875 4575);
FORCEPROP 1 LAST PART_NUMBER E15431-004
J 0
(1875 4325);
DISPLAY 0.617021 (1875 4325);
PAINT BLUE (1875 4325);
FORCEPROP 1 LAST VALUE 22.0UF
J 0
(1875 4525);
DISPLAY 0.617021 (1875 4525);
PAINT SKYBLUE (1875 4525);
FORCEPROP 1 LAST TOLERANCE 20%
J 0
(1875 4425);
DISPLAY 0.617021 (1875 4425);
PAINT SKYBLUE (1875 4425);
FORCEPROP 1 LAST PACK_TYPE 0603V
J 0
(1875 4275);
DISPLAY 0.617021 (1875 4275);
PAINT SKYBLUE (1875 4275);
FORCEPROP 1 LAST VOLTAGE 4V
J 0
(1875 4475);
DISPLAY 0.617021 (1875 4475);
PAINT SKYBLUE (1875 4475);
FORCEPROP 1 LAST MATERIAL X6S
J 0
(1875 4375);
DISPLAY 0.617021 (1875 4375);
PAINT SKYBLUE (1875 4375);
FORCEPROP 1 LASTPIN (1825 4575) $PN 1
J 0
(1835 4555);
DISPLAY 0.617021 (1835 4555);
PAINT WHITE (1835 4555);
FORCEPROP 1 LASTPIN (1825 4375) $PN 2
J 0
(1835 4355);
DISPLAY 0.617021 (1835 4355);
PAINT WHITE (1835 4355);
FORCEPROP 2 LAST CDS_LOCATION C3L26
J 0
(1875 4575);
DISPLAY 0.617021 (1875 4575);
PAINT AQUA (1875 4575);
DISPLAY INVISIBLE (1875 4575);
FORCEPROP 2 LAST BOM_COST SB
J 0
(1875 4675);
DISPLAY 1.361702 (1875 4675);
PAINT ORANGE (1875 4675);
DISPLAY INVISIBLE (1875 4675);
FORCEPROP 2 LAST CDS_LIB dev_discrete
J 0
(1825 4475);
PAINT ORANGE (1825 4475);
DISPLAY INVISIBLE (1825 4475);
FORCEPROP 2 LAST CDS_SEC 1
J 0
(1875 4675);
DISPLAY 1.361702 (1875 4675);
PAINT ORANGE (1875 4675);
DISPLAY INVISIBLE (1875 4675);
FORCEPROP 2 LAST $SEC 1
J 0
(1875 4675);
DISPLAY 0.914894 (1875 4675);
PAINT MONO (1875 4675);
DISPLAY INVISIBLE (1875 4675);
FORCEPROP 1 LAST PATH I3
J 0
(1875 4625);
DISPLAY 0.978723 (1875 4625);
PAINT WHITE (1875 4625);
DISPLAY INVISIBLE (1875 4625);
FORCEPROP 2 LAST ROOM SB_DECOUPLING
J 0
(1875 4625);
DISPLAY 1.361702 (1875 4625);
PAINT ORANGE (1875 4625);
DISPLAY INVISIBLE (1875 4625);
FORCEADD CAP_A..1
(-1100 4050);
FORCEPROP 1 LAST LOCATION C2N11
J 0
(-1050 4150);
DISPLAY 0.617021 (-1050 4150);
PAINT AQUA (-1050 4150);
FORCEPROP 1 LAST PART_NUMBER D97712-004
J 0
(-1050 3900);
DISPLAY 0.617021 (-1050 3900);
PAINT BLUE (-1050 3900);
FORCEPROP 1 LAST VALUE 1.0UF
J 0
(-1050 4100);
DISPLAY 0.617021 (-1050 4100);
PAINT SKYBLUE (-1050 4100);
FORCEPROP 1 LAST TOLERANCE 10%
J 0
(-1050 4000);
DISPLAY 0.617021 (-1050 4000);
PAINT SKYBLUE (-1050 4000);
FORCEPROP 1 LAST PACK_TYPE 0402V
J 0
(-1050 3850);
DISPLAY 0.617021 (-1050 3850);
PAINT SKYBLUE (-1050 3850);
FORCEPROP 1 LAST VOLTAGE 6.3V
J 0
(-1050 4050);
DISPLAY 0.617021 (-1050 4050);
PAINT SKYBLUE (-1050 4050);
FORCEPROP 1 LAST MATERIAL X6S
J 0
(-1050 3950);
DISPLAY 0.617021 (-1050 3950);
PAINT SKYBLUE (-1050 3950);
FORCEPROP 1 LASTPIN (-1100 4150) $PN 1
J 0
(-1090 4130);
DISPLAY 0.617021 (-1090 4130);
PAINT WHITE (-1090 4130);
FORCEPROP 1 LASTPIN (-1100 3950) $PN 2
J 0
(-1090 3930);
DISPLAY 0.617021 (-1090 3930);
PAINT WHITE (-1090 3930);
FORCEPROP 2 LAST CDS_LOCATION C2N11
J 0
(-1050 4150);
DISPLAY 0.617021 (-1050 4150);
PAINT AQUA (-1050 4150);
DISPLAY INVISIBLE (-1050 4150);
FORCEPROP 2 LAST BOM_COST SB
J 0
(-1050 3800);
PAINT MONO (-1050 3800);
DISPLAY INVISIBLE (-1050 3800);
FORCEPROP 2 LAST CDS_LIB dev_discrete
J 0
(-1100 4050);
PAINT ORANGE (-1100 4050);
DISPLAY INVISIBLE (-1100 4050);
FORCEPROP 2 LAST CDS_SEC 1
J 0
(-1050 4250);
PAINT MONO (-1050 4250);
DISPLAY INVISIBLE (-1050 4250);
FORCEPROP 2 LAST $SEC 1
J 0
(-1050 4250);
DISPLAY 0.914894 (-1050 4250);
PAINT MONO (-1050 4250);
DISPLAY INVISIBLE (-1050 4250);
FORCEPROP 1 LAST PATH I30
J 0
(-1050 4200);
DISPLAY 0.978723 (-1050 4200);
PAINT WHITE (-1050 4200);
DISPLAY INVISIBLE (-1050 4200);
FORCEPROP 2 LAST ROOM SB_DECOUPLING
J 0
(-1100 4050);
PAINT WHITE (-1100 4050);
DISPLAY INVISIBLE (-1100 4050);
FORCEADD CAP_A..1
(-1475 4050);
FORCEPROP 1 LAST LOCATION C3N19
J 0
(-1425 4150);
DISPLAY 0.617021 (-1425 4150);
PAINT AQUA (-1425 4150);
FORCEPROP 1 LAST PART_NUMBER D97712-004
J 0
(-1425 3900);
DISPLAY 0.617021 (-1425 3900);
PAINT BLUE (-1425 3900);
FORCEPROP 1 LAST VALUE 1.0UF
J 0
(-1425 4100);
DISPLAY 0.617021 (-1425 4100);
PAINT SKYBLUE (-1425 4100);
FORCEPROP 1 LAST TOLERANCE 10%
J 0
(-1425 4000);
DISPLAY 0.617021 (-1425 4000);
PAINT SKYBLUE (-1425 4000);
FORCEPROP 1 LAST PACK_TYPE 0402V
J 0
(-1425 3850);
DISPLAY 0.617021 (-1425 3850);
PAINT SKYBLUE (-1425 3850);
FORCEPROP 1 LAST VOLTAGE 6.3V
J 0
(-1425 4050);
DISPLAY 0.617021 (-1425 4050);
PAINT SKYBLUE (-1425 4050);
FORCEPROP 1 LAST MATERIAL X6S
J 0
(-1425 3950);
DISPLAY 0.617021 (-1425 3950);
PAINT SKYBLUE (-1425 3950);
FORCEPROP 1 LASTPIN (-1475 4150) $PN 1
J 0
(-1465 4130);
DISPLAY 0.617021 (-1465 4130);
PAINT WHITE (-1465 4130);
FORCEPROP 1 LASTPIN (-1475 3950) $PN 2
J 0
(-1465 3930);
DISPLAY 0.617021 (-1465 3930);
PAINT WHITE (-1465 3930);
FORCEPROP 2 LAST CDS_LOCATION C3N19
J 0
(-1425 4150);
DISPLAY 0.617021 (-1425 4150);
PAINT AQUA (-1425 4150);
DISPLAY INVISIBLE (-1425 4150);
FORCEPROP 2 LAST BOM_COST SB
J 0
(-1425 3800);
PAINT MONO (-1425 3800);
DISPLAY INVISIBLE (-1425 3800);
FORCEPROP 2 LAST CDS_LIB dev_discrete
J 0
(-1475 4050);
PAINT ORANGE (-1475 4050);
DISPLAY INVISIBLE (-1475 4050);
FORCEPROP 2 LAST CDS_SEC 1
J 0
(-1425 4250);
DISPLAY 1.361702 (-1425 4250);
PAINT ORANGE (-1425 4250);
DISPLAY INVISIBLE (-1425 4250);
FORCEPROP 2 LAST $SEC 1
J 0
(-1425 4250);
DISPLAY 0.914894 (-1425 4250);
PAINT MONO (-1425 4250);
DISPLAY INVISIBLE (-1425 4250);
FORCEPROP 1 LAST PATH I31
J 0
(-1425 4200);
DISPLAY 0.978723 (-1425 4200);
PAINT WHITE (-1425 4200);
DISPLAY INVISIBLE (-1425 4200);
FORCEPROP 2 LAST ROOM SB_DECOUPLING
J 0
(-1475 4050);
PAINT WHITE (-1475 4050);
DISPLAY INVISIBLE (-1475 4050);
FORCEADD CAP_A..1
(-1850 4050);
FORCEPROP 1 LAST LOCATION C3N3
J 0
(-1800 4150);
DISPLAY 0.617021 (-1800 4150);
PAINT AQUA (-1800 4150);
FORCEPROP 1 LAST PART_NUMBER D97712-004
J 0
(-1800 3900);
DISPLAY 0.617021 (-1800 3900);
PAINT BLUE (-1800 3900);
FORCEPROP 1 LAST VALUE 1.0UF
J 0
(-1800 4100);
DISPLAY 0.617021 (-1800 4100);
PAINT SKYBLUE (-1800 4100);
FORCEPROP 1 LAST TOLERANCE 10%
J 0
(-1800 4000);
DISPLAY 0.617021 (-1800 4000);
PAINT SKYBLUE (-1800 4000);
FORCEPROP 1 LAST PACK_TYPE 0402V
J 0
(-1800 3850);
DISPLAY 0.617021 (-1800 3850);
PAINT SKYBLUE (-1800 3850);
FORCEPROP 1 LAST VOLTAGE 6.3V
J 0
(-1800 4050);
DISPLAY 0.617021 (-1800 4050);
PAINT SKYBLUE (-1800 4050);
FORCEPROP 1 LAST MATERIAL X6S
J 0
(-1800 3950);
DISPLAY 0.617021 (-1800 3950);
PAINT SKYBLUE (-1800 3950);
FORCEPROP 1 LASTPIN (-1850 4150) $PN 1
J 0
(-1840 4130);
DISPLAY 0.617021 (-1840 4130);
PAINT WHITE (-1840 4130);
FORCEPROP 1 LASTPIN (-1850 3950) $PN 2
J 0
(-1840 3930);
DISPLAY 0.617021 (-1840 3930);
PAINT WHITE (-1840 3930);
FORCEPROP 2 LAST CDS_LOCATION C3N3
J 0
(-1800 4150);
DISPLAY 0.617021 (-1800 4150);
PAINT AQUA (-1800 4150);
DISPLAY INVISIBLE (-1800 4150);
FORCEPROP 2 LAST BOM_COST SB
J 0
(-1800 3800);
PAINT MONO (-1800 3800);
DISPLAY INVISIBLE (-1800 3800);
FORCEPROP 2 LAST CDS_LIB dev_discrete
J 0
(-1850 4050);
PAINT ORANGE (-1850 4050);
DISPLAY INVISIBLE (-1850 4050);
FORCEPROP 2 LAST CDS_SEC 1
J 0
(-1800 4250);
DISPLAY 1.361702 (-1800 4250);
PAINT ORANGE (-1800 4250);
DISPLAY INVISIBLE (-1800 4250);
FORCEPROP 2 LAST $SEC 1
J 0
(-1800 4250);
DISPLAY 0.914894 (-1800 4250);
PAINT MONO (-1800 4250);
DISPLAY INVISIBLE (-1800 4250);
FORCEPROP 1 LAST PATH I32
J 0
(-1800 4200);
DISPLAY 0.978723 (-1800 4200);
PAINT WHITE (-1800 4200);
DISPLAY INVISIBLE (-1800 4200);
FORCEPROP 2 LAST ROOM SB_DECOUPLING
J 0
(-1850 4050);
PAINT WHITE (-1850 4050);
DISPLAY INVISIBLE (-1850 4050);
FORCEADD GND..1
(-1750 3750);
FORCEPROP 3 LASTPIN (-1750 3800) SIG_NAME GND\g
J 0
(-1740 3810);
DISPLAY 0.659574 (-1740 3810);
PAINT MONO (-1740 3810);
DISPLAY INVISIBLE (-1740 3810);
FORCEPROP 1 LAST VOLTAGE 0
J 0
(-1750 3750);
PAINT SKYBLUE (-1750 3750);
DISPLAY INVISIBLE (-1750 3750);
FORCEPROP 1 LAST SIZE 1B
J 0
(-1675 3700);
DISPLAY 1.404255 (-1675 3700);
PAINT GREEN (-1675 3700);
DISPLAY INVISIBLE (-1675 3700);
FORCEPROP 2 LAST CDS_LIB mstr_symbols
J 0
(-1750 3750);
PAINT ORANGE (-1750 3750);
DISPLAY INVISIBLE (-1750 3750);
FORCEPROP 2 LAST BOM_COST SB
J 0
(-1800 3825);
PAINT MONO (-1800 3825);
DISPLAY INVISIBLE (-1800 3825);
FORCEPROP 1 LAST BODY_TYPE PLUMBING
J 0
(-1795 3707);
DISPLAY 0.340426 (-1795 3707);
PAINT GREEN (-1795 3707);
DISPLAY INVISIBLE (-1795 3707);
FORCEPROP 1 LAST PATH I33
J 0
(-1675 3750);
DISPLAY 0.872340 (-1675 3750);
PAINT AQUA (-1675 3750);
DISPLAY INVISIBLE (-1675 3750);
FORCEPROP 2 LAST ROOM SB_DECOUPLING
J 0
(-2225 3825);
PAINT WHITE (-2225 3825);
DISPLAY INVISIBLE (-2225 3825);
FORCEPROP 1 LAST HDL_POWER GND
J 0
(-1750 3900);
DISPLAY 1.404255 (-1750 3900);
PAINT GREEN (-1750 3900);
DISPLAY INVISIBLE (-1750 3900);
FORCEADD CAP_A..1
(-1075 3025);
FORCEPROP 1 LAST LOCATION C3N1
J 0
(-1025 3125);
DISPLAY 0.617021 (-1025 3125);
PAINT AQUA (-1025 3125);
FORCEPROP 1 LAST PART_NUMBER D97712-004
J 0
(-1025 2875);
DISPLAY 0.617021 (-1025 2875);
PAINT BLUE (-1025 2875);
FORCEPROP 1 LAST VALUE 1.0UF
J 0
(-1025 3075);
DISPLAY 0.617021 (-1025 3075);
PAINT SKYBLUE (-1025 3075);
FORCEPROP 1 LAST TOLERANCE 10%
J 0
(-1025 2975);
DISPLAY 0.617021 (-1025 2975);
PAINT SKYBLUE (-1025 2975);
FORCEPROP 1 LAST PACK_TYPE 0402V
J 0
(-1025 2825);
DISPLAY 0.617021 (-1025 2825);
PAINT SKYBLUE (-1025 2825);
FORCEPROP 1 LAST VOLTAGE 6.3V
J 0
(-1025 3025);
DISPLAY 0.617021 (-1025 3025);
PAINT SKYBLUE (-1025 3025);
FORCEPROP 1 LAST MATERIAL X6S
J 0
(-1025 2925);
DISPLAY 0.617021 (-1025 2925);
PAINT SKYBLUE (-1025 2925);
FORCEPROP 1 LASTPIN (-1075 3125) $PN 1
J 0
(-1065 3105);
DISPLAY 0.617021 (-1065 3105);
PAINT WHITE (-1065 3105);
FORCEPROP 1 LASTPIN (-1075 2925) $PN 2
J 0
(-1065 2905);
DISPLAY 0.617021 (-1065 2905);
PAINT WHITE (-1065 2905);
FORCEPROP 2 LAST CDS_LOCATION C3N1
J 0
(-1025 3125);
DISPLAY 0.617021 (-1025 3125);
PAINT AQUA (-1025 3125);
DISPLAY INVISIBLE (-1025 3125);
FORCEPROP 2 LAST BOM_COST SB
J 0
(-1025 2775);
PAINT MONO (-1025 2775);
DISPLAY INVISIBLE (-1025 2775);
FORCEPROP 2 LAST CDS_LIB dev_discrete
J 0
(-1075 3025);
PAINT ORANGE (-1075 3025);
DISPLAY INVISIBLE (-1075 3025);
FORCEPROP 2 LAST CDS_SEC 1
J 0
(-1025 3225);
PAINT MONO (-1025 3225);
DISPLAY INVISIBLE (-1025 3225);
FORCEPROP 2 LAST $SEC 1
J 0
(-1025 3225);
DISPLAY 0.914894 (-1025 3225);
PAINT MONO (-1025 3225);
DISPLAY INVISIBLE (-1025 3225);
FORCEPROP 1 LAST PATH I34
J 0
(-1025 3175);
DISPLAY 0.978723 (-1025 3175);
PAINT WHITE (-1025 3175);
DISPLAY INVISIBLE (-1025 3175);
FORCEPROP 2 LAST ROOM SB_DECOUPLING
J 0
(-1075 3025);
PAINT WHITE (-1075 3025);
DISPLAY INVISIBLE (-1075 3025);
FORCEADD CAP_A..1
(-1450 3025);
FORCEPROP 1 LAST LOCATION C3N7
J 0
(-1400 3125);
DISPLAY 0.617021 (-1400 3125);
PAINT AQUA (-1400 3125);
FORCEPROP 1 LAST PART_NUMBER D97712-004
J 0
(-1400 2875);
DISPLAY 0.617021 (-1400 2875);
PAINT BLUE (-1400 2875);
FORCEPROP 1 LAST VALUE 1.0UF
J 0
(-1400 3075);
DISPLAY 0.617021 (-1400 3075);
PAINT SKYBLUE (-1400 3075);
FORCEPROP 1 LAST TOLERANCE 10%
J 0
(-1400 2975);
DISPLAY 0.617021 (-1400 2975);
PAINT SKYBLUE (-1400 2975);
FORCEPROP 1 LAST PACK_TYPE 0402V
J 0
(-1400 2825);
DISPLAY 0.617021 (-1400 2825);
PAINT SKYBLUE (-1400 2825);
FORCEPROP 1 LAST VOLTAGE 6.3V
J 0
(-1400 3025);
DISPLAY 0.617021 (-1400 3025);
PAINT SKYBLUE (-1400 3025);
FORCEPROP 1 LAST MATERIAL X6S
J 0
(-1400 2925);
DISPLAY 0.617021 (-1400 2925);
PAINT SKYBLUE (-1400 2925);
FORCEPROP 1 LASTPIN (-1450 3125) $PN 1
J 0
(-1440 3105);
DISPLAY 0.617021 (-1440 3105);
PAINT WHITE (-1440 3105);
FORCEPROP 1 LASTPIN (-1450 2925) $PN 2
J 0
(-1440 2905);
DISPLAY 0.617021 (-1440 2905);
PAINT WHITE (-1440 2905);
FORCEPROP 2 LAST CDS_LOCATION C3N7
J 0
(-1400 3125);
DISPLAY 0.617021 (-1400 3125);
PAINT AQUA (-1400 3125);
DISPLAY INVISIBLE (-1400 3125);
FORCEPROP 2 LAST BOM_COST SB
J 0
(-1400 2775);
PAINT MONO (-1400 2775);
DISPLAY INVISIBLE (-1400 2775);
FORCEPROP 2 LAST CDS_LIB dev_discrete
J 0
(-1450 3025);
PAINT ORANGE (-1450 3025);
DISPLAY INVISIBLE (-1450 3025);
FORCEPROP 2 LAST CDS_SEC 1
J 0
(-1400 3225);
DISPLAY 1.361702 (-1400 3225);
PAINT ORANGE (-1400 3225);
DISPLAY INVISIBLE (-1400 3225);
FORCEPROP 2 LAST $SEC 1
J 0
(-1400 3225);
DISPLAY 0.914894 (-1400 3225);
PAINT MONO (-1400 3225);
DISPLAY INVISIBLE (-1400 3225);
FORCEPROP 1 LAST PATH I35
J 0
(-1400 3175);
DISPLAY 0.978723 (-1400 3175);
PAINT WHITE (-1400 3175);
DISPLAY INVISIBLE (-1400 3175);
FORCEPROP 2 LAST ROOM SB_DECOUPLING
J 0
(-1450 3025);
PAINT WHITE (-1450 3025);
DISPLAY INVISIBLE (-1450 3025);
FORCEADD CAP_A..1
(-1825 3025);
FORCEPROP 1 LAST LOCATION C3N16
J 0
(-1775 3125);
DISPLAY 0.617021 (-1775 3125);
PAINT AQUA (-1775 3125);
FORCEPROP 1 LAST PART_NUMBER D97712-004
J 0
(-1775 2875);
DISPLAY 0.617021 (-1775 2875);
PAINT BLUE (-1775 2875);
FORCEPROP 1 LAST VALUE 1.0UF
J 0
(-1775 3075);
DISPLAY 0.617021 (-1775 3075);
PAINT SKYBLUE (-1775 3075);
FORCEPROP 1 LAST TOLERANCE 10%
J 0
(-1775 2975);
DISPLAY 0.617021 (-1775 2975);
PAINT SKYBLUE (-1775 2975);
FORCEPROP 1 LAST PACK_TYPE 0402V
J 0
(-1775 2825);
DISPLAY 0.617021 (-1775 2825);
PAINT SKYBLUE (-1775 2825);
FORCEPROP 1 LAST VOLTAGE 6.3V
J 0
(-1775 3025);
DISPLAY 0.617021 (-1775 3025);
PAINT SKYBLUE (-1775 3025);
FORCEPROP 1 LAST MATERIAL X6S
J 0
(-1775 2925);
DISPLAY 0.617021 (-1775 2925);
PAINT SKYBLUE (-1775 2925);
FORCEPROP 1 LASTPIN (-1825 3125) $PN 1
J 0
(-1815 3105);
DISPLAY 0.617021 (-1815 3105);
PAINT WHITE (-1815 3105);
FORCEPROP 1 LASTPIN (-1825 2925) $PN 2
J 0
(-1815 2905);
DISPLAY 0.617021 (-1815 2905);
PAINT WHITE (-1815 2905);
FORCEPROP 2 LAST CDS_LOCATION C3N16
J 0
(-1775 3125);
DISPLAY 0.617021 (-1775 3125);
PAINT AQUA (-1775 3125);
DISPLAY INVISIBLE (-1775 3125);
FORCEPROP 2 LAST BOM_COST SB
J 0
(-1775 2775);
PAINT MONO (-1775 2775);
DISPLAY INVISIBLE (-1775 2775);
FORCEPROP 2 LAST CDS_LIB dev_discrete
J 0
(-1825 3025);
PAINT ORANGE (-1825 3025);
DISPLAY INVISIBLE (-1825 3025);
FORCEPROP 2 LAST CDS_SEC 1
J 0
(-1775 3225);
DISPLAY 1.361702 (-1775 3225);
PAINT ORANGE (-1775 3225);
DISPLAY INVISIBLE (-1775 3225);
FORCEPROP 2 LAST $SEC 1
J 0
(-1775 3225);
DISPLAY 0.914894 (-1775 3225);
PAINT MONO (-1775 3225);
DISPLAY INVISIBLE (-1775 3225);
FORCEPROP 1 LAST PATH I36
J 0
(-1775 3175);
DISPLAY 0.978723 (-1775 3175);
PAINT WHITE (-1775 3175);
DISPLAY INVISIBLE (-1775 3175);
FORCEPROP 2 LAST ROOM SB_DECOUPLING
J 0
(-1825 3025);
PAINT WHITE (-1825 3025);
DISPLAY INVISIBLE (-1825 3025);
FORCEADD GND..1
(-1725 2725);
FORCEPROP 3 LASTPIN (-1725 2775) SIG_NAME GND\g
J 0
(-1715 2785);
DISPLAY 0.659574 (-1715 2785);
PAINT MONO (-1715 2785);
DISPLAY INVISIBLE (-1715 2785);
FORCEPROP 1 LAST VOLTAGE 0
J 0
(-1725 2725);
PAINT SKYBLUE (-1725 2725);
DISPLAY INVISIBLE (-1725 2725);
FORCEPROP 1 LAST SIZE 1B
J 0
(-1650 2675);
DISPLAY 1.404255 (-1650 2675);
PAINT GREEN (-1650 2675);
DISPLAY INVISIBLE (-1650 2675);
FORCEPROP 2 LAST CDS_LIB mstr_symbols
J 0
(-1725 2725);
PAINT ORANGE (-1725 2725);
DISPLAY INVISIBLE (-1725 2725);
FORCEPROP 2 LAST BOM_COST SB
J 0
(-1775 2800);
PAINT MONO (-1775 2800);
DISPLAY INVISIBLE (-1775 2800);
FORCEPROP 1 LAST BODY_TYPE PLUMBING
J 0
(-1770 2682);
DISPLAY 0.340426 (-1770 2682);
PAINT GREEN (-1770 2682);
DISPLAY INVISIBLE (-1770 2682);
FORCEPROP 1 LAST PATH I37
J 0
(-1650 2725);
DISPLAY 0.872340 (-1650 2725);
PAINT AQUA (-1650 2725);
DISPLAY INVISIBLE (-1650 2725);
FORCEPROP 2 LAST ROOM SB_DECOUPLING
J 0
(-2200 2800);
PAINT WHITE (-2200 2800);
DISPLAY INVISIBLE (-2200 2800);
FORCEPROP 1 LAST HDL_POWER GND
J 0
(-1725 2875);
DISPLAY 1.404255 (-1725 2875);
PAINT GREEN (-1725 2875);
DISPLAY INVISIBLE (-1725 2875);
FORCEADD CAP..1
(-650 1900);
FORCEPROP 1 LAST LOCATION C7A32
J 0
(-600 2000);
DISPLAY 0.617021 (-600 2000);
PAINT AQUA (-600 2000);
FORCEPROP 1 LAST PART_NUMBER C95333-006
J 0
(-600 1750);
DISPLAY 0.617021 (-600 1750);
PAINT BLUE (-600 1750);
FORCEPROP 1 LAST VALUE 47UF
J 0
(-600 1950);
DISPLAY 0.617021 (-600 1950);
PAINT SKYBLUE (-600 1950);
FORCEPROP 1 LAST TOLERANCE 20%
J 0
(-600 1850);
DISPLAY 0.617021 (-600 1850);
PAINT SKYBLUE (-600 1850);
FORCEPROP 1 LAST PACK_TYPE 0805
J 0
(-600 1700);
DISPLAY 0.617021 (-600 1700);
PAINT SKYBLUE (-600 1700);
FORCEPROP 1 LAST VOLTAGE 4V
J 0
(-600 1900);
DISPLAY 0.617021 (-600 1900);
PAINT SKYBLUE (-600 1900);
FORCEPROP 1 LAST MATERIAL X6S
J 0
(-600 1800);
DISPLAY 0.617021 (-600 1800);
PAINT SKYBLUE (-600 1800);
FORCEPROP 1 LASTPIN (-650 1800) $PN 2
J 0
(-640 1780);
DISPLAY 0.617021 (-640 1780);
PAINT WHITE (-640 1780);
FORCEPROP 1 LASTPIN (-650 2000) $PN 1
J 0
(-640 1980);
DISPLAY 0.617021 (-640 1980);
PAINT WHITE (-640 1980);
FORCEPROP 2 LAST CDS_LIB mstr_discrete
J 0
(-650 1900);
PAINT MONO (-650 1900);
DISPLAY INVISIBLE (-650 1900);
FORCEPROP 2 LAST BOM_COST SB
J 0
(-600 2100);
DISPLAY 1.361702 (-600 2100);
PAINT ORANGE (-600 2100);
DISPLAY INVISIBLE (-600 2100);
FORCEPROP 2 LAST CDS_SEC 1
J 0
(-600 2100);
DISPLAY 1.361702 (-600 2100);
PAINT ORANGE (-600 2100);
DISPLAY INVISIBLE (-600 2100);
FORCEPROP 2 LAST $SEC 1
J 0
(-600 2100);
DISPLAY 0.914894 (-600 2100);
PAINT MONO (-600 2100);
DISPLAY INVISIBLE (-600 2100);
FORCEPROP 2 LAST CDS_LOCATION C7A32
J 0
(-600 2000);
DISPLAY 0.617021 (-600 2000);
PAINT AQUA (-600 2000);
DISPLAY INVISIBLE (-600 2000);
FORCEPROP 1 LAST PATH I38
J 0
(-600 2050);
DISPLAY 0.978723 (-600 2050);
PAINT WHITE (-600 2050);
DISPLAY INVISIBLE (-600 2050);
FORCEPROP 2 LAST ROOM SB_DECOUPLING
J 0
(-600 2050);
DISPLAY 1.361702 (-600 2050);
PAINT ORANGE (-600 2050);
DISPLAY INVISIBLE (-600 2050);
FORCEADD PVNN_PCH_STBY..1
(-875 2200);
FORCEPROP 3 LASTPIN (-875 2150) SIG_NAME PVNN_PCH_STBY\g
J 0
(-865 2160);
DISPLAY 0.659574 (-865 2160);
PAINT MONO (-865 2160);
DISPLAY INVISIBLE (-865 2160);
FORCEPROP 1 LAST VOLTAGE 1.0V
J 0
(-920 2157);
DISPLAY 0.340426 (-920 2157);
PAINT SKYBLUE (-920 2157);
DISPLAY INVISIBLE (-920 2157);
FORCEPROP 2 LAST CDS_LIB mstr_symbols
J 0
(-875 2200);
PAINT ORANGE (-875 2200);
DISPLAY INVISIBLE (-875 2200);
FORCEPROP 2 LAST BOM_COST SB
J 0
(-875 2300);
DISPLAY 1.361702 (-875 2300);
PAINT ORANGE (-875 2300);
DISPLAY INVISIBLE (-875 2300);
FORCEPROP 1 LAST BODY_TYPE PLUMBING
J 0
(-920 2157);
DISPLAY 0.340426 (-920 2157);
PAINT GREEN (-920 2157);
DISPLAY INVISIBLE (-920 2157);
FORCEPROP 1 LAST PATH I39
J 0
(-825 2225);
DISPLAY 0.872340 (-825 2225);
PAINT AQUA (-825 2225);
DISPLAY INVISIBLE (-825 2225);
FORCEPROP 2 LAST ROOM SB_DECOUPLING
J 0
(-875 2300);
DISPLAY 1.361702 (-875 2300);
PAINT ORANGE (-875 2300);
DISPLAY INVISIBLE (-875 2300);
FORCEPROP 1 LAST HDL_POWER PVNN_PCH_STBY
J 1
(-875 2250);
DISPLAY 0.872340 (-875 2250);
PAINT GREEN (-875 2250);
DISPLAY INVISIBLE (-875 2250);
FORCEADD CAP_A..1
(1450 4475);
FORCEPROP 1 LAST LOCATION C3L27
J 0
(1500 4575);
DISPLAY 0.617021 (1500 4575);
PAINT AQUA (1500 4575);
FORCEPROP 1 LAST PART_NUMBER E15431-004
J 0
(1500 4325);
DISPLAY 0.617021 (1500 4325);
PAINT BLUE (1500 4325);
FORCEPROP 1 LAST VALUE 22.0UF
J 0
(1500 4525);
DISPLAY 0.617021 (1500 4525);
PAINT SKYBLUE (1500 4525);
FORCEPROP 1 LAST TOLERANCE 20%
J 0
(1500 4425);
DISPLAY 0.617021 (1500 4425);
PAINT SKYBLUE (1500 4425);
FORCEPROP 1 LAST PACK_TYPE 0603V
J 0
(1500 4275);
DISPLAY 0.617021 (1500 4275);
PAINT SKYBLUE (1500 4275);
FORCEPROP 1 LAST VOLTAGE 4V
J 0
(1500 4475);
DISPLAY 0.617021 (1500 4475);
PAINT SKYBLUE (1500 4475);
FORCEPROP 1 LAST MATERIAL X6S
J 0
(1500 4375);
DISPLAY 0.617021 (1500 4375);
PAINT SKYBLUE (1500 4375);
FORCEPROP 1 LASTPIN (1450 4575) $PN 1
J 0
(1460 4555);
DISPLAY 0.617021 (1460 4555);
PAINT WHITE (1460 4555);
FORCEPROP 1 LASTPIN (1450 4375) $PN 2
J 0
(1460 4355);
DISPLAY 0.617021 (1460 4355);
PAINT WHITE (1460 4355);
FORCEPROP 2 LAST CDS_LOCATION C3L27
J 0
(1500 4575);
DISPLAY 0.617021 (1500 4575);
PAINT AQUA (1500 4575);
DISPLAY INVISIBLE (1500 4575);
FORCEPROP 2 LAST BOM_COST SB
J 0
(1500 4675);
DISPLAY 1.361702 (1500 4675);
PAINT ORANGE (1500 4675);
DISPLAY INVISIBLE (1500 4675);
FORCEPROP 2 LAST CDS_LIB dev_discrete
J 0
(1450 4475);
PAINT ORANGE (1450 4475);
DISPLAY INVISIBLE (1450 4475);
FORCEPROP 2 LAST CDS_SEC 1
J 0
(1500 4675);
DISPLAY 1.361702 (1500 4675);
PAINT ORANGE (1500 4675);
DISPLAY INVISIBLE (1500 4675);
FORCEPROP 2 LAST $SEC 1
J 0
(1500 4675);
DISPLAY 0.914894 (1500 4675);
PAINT MONO (1500 4675);
DISPLAY INVISIBLE (1500 4675);
FORCEPROP 1 LAST PATH I4
J 0
(1500 4625);
DISPLAY 0.978723 (1500 4625);
PAINT WHITE (1500 4625);
DISPLAY INVISIBLE (1500 4625);
FORCEPROP 2 LAST ROOM SB_DECOUPLING
J 0
(1500 4625);
DISPLAY 1.361702 (1500 4625);
PAINT ORANGE (1500 4625);
DISPLAY INVISIBLE (1500 4625);
FORCEADD CAP..1
(-1100 1900);
FORCEPROP 1 LAST LOCATION C7A31
J 0
(-1050 2000);
DISPLAY 0.617021 (-1050 2000);
PAINT AQUA (-1050 2000);
FORCEPROP 1 LAST PART_NUMBER C95333-006
J 0
(-1050 1750);
DISPLAY 0.617021 (-1050 1750);
PAINT BLUE (-1050 1750);
FORCEPROP 1 LAST VALUE 47UF
J 0
(-1050 1950);
DISPLAY 0.617021 (-1050 1950);
PAINT SKYBLUE (-1050 1950);
FORCEPROP 1 LAST TOLERANCE 20%
J 0
(-1050 1850);
DISPLAY 0.617021 (-1050 1850);
PAINT SKYBLUE (-1050 1850);
FORCEPROP 1 LAST PACK_TYPE 0805
J 0
(-1050 1700);
DISPLAY 0.617021 (-1050 1700);
PAINT SKYBLUE (-1050 1700);
FORCEPROP 1 LAST VOLTAGE 4V
J 0
(-1050 1900);
DISPLAY 0.617021 (-1050 1900);
PAINT SKYBLUE (-1050 1900);
FORCEPROP 1 LAST MATERIAL X6S
J 0
(-1050 1800);
DISPLAY 0.617021 (-1050 1800);
PAINT SKYBLUE (-1050 1800);
FORCEPROP 1 LASTPIN (-1100 1800) $PN 2
J 0
(-1090 1780);
DISPLAY 0.617021 (-1090 1780);
PAINT WHITE (-1090 1780);
FORCEPROP 1 LASTPIN (-1100 2000) $PN 1
J 0
(-1090 1980);
DISPLAY 0.617021 (-1090 1980);
PAINT WHITE (-1090 1980);
FORCEPROP 2 LAST CDS_LIB mstr_discrete
J 0
(-1100 1900);
PAINT MONO (-1100 1900);
DISPLAY INVISIBLE (-1100 1900);
FORCEPROP 2 LAST BOM_COST SB
J 0
(-1050 2100);
DISPLAY 1.361702 (-1050 2100);
PAINT ORANGE (-1050 2100);
DISPLAY INVISIBLE (-1050 2100);
FORCEPROP 2 LAST CDS_SEC 1
J 0
(-1050 2100);
DISPLAY 1.361702 (-1050 2100);
PAINT ORANGE (-1050 2100);
DISPLAY INVISIBLE (-1050 2100);
FORCEPROP 2 LAST $SEC 1
J 0
(-1050 2100);
DISPLAY 0.914894 (-1050 2100);
PAINT MONO (-1050 2100);
DISPLAY INVISIBLE (-1050 2100);
FORCEPROP 2 LAST CDS_LOCATION C7A31
J 0
(-1050 2000);
DISPLAY 0.617021 (-1050 2000);
PAINT AQUA (-1050 2000);
DISPLAY INVISIBLE (-1050 2000);
FORCEPROP 1 LAST PATH I40
J 0
(-1050 2050);
DISPLAY 0.978723 (-1050 2050);
PAINT WHITE (-1050 2050);
DISPLAY INVISIBLE (-1050 2050);
FORCEPROP 2 LAST ROOM SB_DECOUPLING
J 0
(-1050 2050);
DISPLAY 1.361702 (-1050 2050);
PAINT ORANGE (-1050 2050);
DISPLAY INVISIBLE (-1050 2050);
FORCEADD GND..1
(-875 1525);
FORCEPROP 3 LASTPIN (-875 1575) SIG_NAME GND\g
J 0
(-865 1585);
DISPLAY 0.659574 (-865 1585);
PAINT MONO (-865 1585);
DISPLAY INVISIBLE (-865 1585);
FORCEPROP 1 LAST VOLTAGE 0.0V
J 0
(-920 1482);
DISPLAY 0.340426 (-920 1482);
PAINT SKYBLUE (-920 1482);
DISPLAY INVISIBLE (-920 1482);
FORCEPROP 1 LAST SIZE 1B
J 0
(-800 1475);
DISPLAY 1.170213 (-800 1475);
PAINT AQUA (-800 1475);
DISPLAY INVISIBLE (-800 1475);
FORCEPROP 2 LAST CDS_LIB mstr_symbols
J 0
(-875 1525);
PAINT MONO (-875 1525);
DISPLAY INVISIBLE (-875 1525);
FORCEPROP 2 LAST BOM_COST SB
J 0
(-850 1600);
DISPLAY 1.361702 (-850 1600);
PAINT ORANGE (-850 1600);
DISPLAY INVISIBLE (-850 1600);
FORCEPROP 1 LAST BODY_TYPE PLUMBING
J 0
(-920 1482);
DISPLAY 0.340426 (-920 1482);
PAINT GREEN (-920 1482);
DISPLAY INVISIBLE (-920 1482);
FORCEPROP 1 LAST PATH I41
J 0
(-800 1525);
DISPLAY 0.872340 (-800 1525);
PAINT AQUA (-800 1525);
DISPLAY INVISIBLE (-800 1525);
FORCEPROP 2 LAST ROOM SB_DECOUPLING
J 0
(-850 1600);
DISPLAY 1.361702 (-850 1600);
PAINT ORANGE (-850 1600);
DISPLAY INVISIBLE (-850 1600);
FORCEPROP 1 LAST HDL_POWER GND
J 0
(-875 1675);
DISPLAY 1.170213 (-875 1675);
PAINT GREEN (-875 1675);
DISPLAY INVISIBLE (-875 1675);
FORCEADD CAP_A..1
(-2225 4050);
FORCEPROP 1 LAST LOCATION C3N18
J 0
(-2175 4150);
DISPLAY 0.617021 (-2175 4150);
PAINT AQUA (-2175 4150);
FORCEPROP 1 LAST PART_NUMBER D97712-004
J 0
(-2175 3900);
DISPLAY 0.617021 (-2175 3900);
PAINT BLUE (-2175 3900);
FORCEPROP 1 LAST VALUE 1.0UF
J 0
(-2175 4100);
DISPLAY 0.617021 (-2175 4100);
PAINT SKYBLUE (-2175 4100);
FORCEPROP 1 LAST TOLERANCE 10%
J 0
(-2175 4000);
DISPLAY 0.617021 (-2175 4000);
PAINT SKYBLUE (-2175 4000);
FORCEPROP 1 LAST PACK_TYPE 0402V
J 0
(-2175 3850);
DISPLAY 0.617021 (-2175 3850);
PAINT SKYBLUE (-2175 3850);
FORCEPROP 1 LAST VOLTAGE 6.3V
J 0
(-2175 4050);
DISPLAY 0.617021 (-2175 4050);
PAINT SKYBLUE (-2175 4050);
FORCEPROP 1 LAST MATERIAL X6S
J 0
(-2175 3950);
DISPLAY 0.617021 (-2175 3950);
PAINT SKYBLUE (-2175 3950);
FORCEPROP 1 LASTPIN (-2225 4150) $PN 1
J 0
(-2215 4130);
DISPLAY 0.617021 (-2215 4130);
PAINT WHITE (-2215 4130);
FORCEPROP 1 LASTPIN (-2225 3950) $PN 2
J 0
(-2215 3930);
DISPLAY 0.617021 (-2215 3930);
PAINT WHITE (-2215 3930);
FORCEPROP 2 LAST CDS_LOCATION C3N18
J 0
(-2175 4150);
DISPLAY 0.617021 (-2175 4150);
PAINT AQUA (-2175 4150);
DISPLAY INVISIBLE (-2175 4150);
FORCEPROP 2 LAST BOM_COST SB
J 0
(-2175 3800);
PAINT MONO (-2175 3800);
DISPLAY INVISIBLE (-2175 3800);
FORCEPROP 2 LAST CDS_LIB dev_discrete
J 0
(-2225 4050);
PAINT ORANGE (-2225 4050);
DISPLAY INVISIBLE (-2225 4050);
FORCEPROP 2 LAST CDS_SEC 1
J 0
(-2175 4250);
DISPLAY 1.361702 (-2175 4250);
PAINT ORANGE (-2175 4250);
DISPLAY INVISIBLE (-2175 4250);
FORCEPROP 2 LAST $SEC 1
J 0
(-2175 4250);
DISPLAY 0.914894 (-2175 4250);
PAINT MONO (-2175 4250);
DISPLAY INVISIBLE (-2175 4250);
FORCEPROP 1 LAST PATH I42
J 0
(-2175 4200);
DISPLAY 0.978723 (-2175 4200);
PAINT WHITE (-2175 4200);
DISPLAY INVISIBLE (-2175 4200);
FORCEPROP 2 LAST ROOM SB_DECOUPLING
J 0
(-2225 4050);
PAINT WHITE (-2225 4050);
DISPLAY INVISIBLE (-2225 4050);
FORCEADD CAP_A..1
(-2625 4050);
FORCEPROP 1 LAST LOCATION C3N2
J 0
(-2575 4150);
DISPLAY 0.617021 (-2575 4150);
PAINT AQUA (-2575 4150);
FORCEPROP 1 LAST PART_NUMBER D97712-004
J 0
(-2575 3900);
DISPLAY 0.617021 (-2575 3900);
PAINT BLUE (-2575 3900);
FORCEPROP 1 LAST VALUE 1.0UF
J 0
(-2575 4100);
DISPLAY 0.617021 (-2575 4100);
PAINT SKYBLUE (-2575 4100);
FORCEPROP 1 LAST TOLERANCE 10%
J 0
(-2575 4000);
DISPLAY 0.617021 (-2575 4000);
PAINT SKYBLUE (-2575 4000);
FORCEPROP 1 LAST PACK_TYPE 0402V
J 0
(-2575 3850);
DISPLAY 0.617021 (-2575 3850);
PAINT SKYBLUE (-2575 3850);
FORCEPROP 1 LAST VOLTAGE 6.3V
J 0
(-2575 4050);
DISPLAY 0.617021 (-2575 4050);
PAINT SKYBLUE (-2575 4050);
FORCEPROP 1 LAST MATERIAL X6S
J 0
(-2575 3950);
DISPLAY 0.617021 (-2575 3950);
PAINT SKYBLUE (-2575 3950);
FORCEPROP 1 LASTPIN (-2625 4150) $PN 1
J 0
(-2615 4130);
DISPLAY 0.617021 (-2615 4130);
PAINT WHITE (-2615 4130);
FORCEPROP 1 LASTPIN (-2625 3950) $PN 2
J 0
(-2615 3930);
DISPLAY 0.617021 (-2615 3930);
PAINT WHITE (-2615 3930);
FORCEPROP 2 LAST CDS_LOCATION C3N2
J 0
(-2575 4150);
DISPLAY 0.617021 (-2575 4150);
PAINT AQUA (-2575 4150);
DISPLAY INVISIBLE (-2575 4150);
FORCEPROP 2 LAST BOM_COST SB
J 0
(-2575 3800);
PAINT MONO (-2575 3800);
DISPLAY INVISIBLE (-2575 3800);
FORCEPROP 2 LAST CDS_LIB dev_discrete
J 0
(-2625 4050);
PAINT ORANGE (-2625 4050);
DISPLAY INVISIBLE (-2625 4050);
FORCEPROP 2 LAST CDS_SEC 1
J 0
(-2575 4250);
DISPLAY 1.361702 (-2575 4250);
PAINT ORANGE (-2575 4250);
DISPLAY INVISIBLE (-2575 4250);
FORCEPROP 2 LAST $SEC 1
J 0
(-2575 4250);
DISPLAY 0.914894 (-2575 4250);
PAINT MONO (-2575 4250);
DISPLAY INVISIBLE (-2575 4250);
FORCEPROP 1 LAST PATH I43
J 0
(-2575 4200);
DISPLAY 0.978723 (-2575 4200);
PAINT WHITE (-2575 4200);
DISPLAY INVISIBLE (-2575 4200);
FORCEPROP 2 LAST ROOM SB_DECOUPLING
J 0
(-2625 4050);
PAINT WHITE (-2625 4050);
DISPLAY INVISIBLE (-2625 4050);
FORCEADD CAP_A..1
(-2200 3025);
FORCEPROP 1 LAST LOCATION C3N6
J 0
(-2150 3125);
DISPLAY 0.617021 (-2150 3125);
PAINT AQUA (-2150 3125);
FORCEPROP 1 LAST PART_NUMBER D97712-004
J 0
(-2150 2875);
DISPLAY 0.617021 (-2150 2875);
PAINT BLUE (-2150 2875);
FORCEPROP 1 LAST VALUE 1.0UF
J 0
(-2150 3075);
DISPLAY 0.617021 (-2150 3075);
PAINT SKYBLUE (-2150 3075);
FORCEPROP 1 LAST TOLERANCE 10%
J 0
(-2150 2975);
DISPLAY 0.617021 (-2150 2975);
PAINT SKYBLUE (-2150 2975);
FORCEPROP 1 LAST PACK_TYPE 0402V
J 0
(-2150 2825);
DISPLAY 0.617021 (-2150 2825);
PAINT SKYBLUE (-2150 2825);
FORCEPROP 1 LAST VOLTAGE 6.3V
J 0
(-2150 3025);
DISPLAY 0.617021 (-2150 3025);
PAINT SKYBLUE (-2150 3025);
FORCEPROP 1 LAST MATERIAL X6S
J 0
(-2150 2925);
DISPLAY 0.617021 (-2150 2925);
PAINT SKYBLUE (-2150 2925);
FORCEPROP 1 LASTPIN (-2200 3125) $PN 1
J 0
(-2190 3105);
DISPLAY 0.617021 (-2190 3105);
PAINT WHITE (-2190 3105);
FORCEPROP 1 LASTPIN (-2200 2925) $PN 2
J 0
(-2190 2905);
DISPLAY 0.617021 (-2190 2905);
PAINT WHITE (-2190 2905);
FORCEPROP 2 LAST CDS_LOCATION C3N6
J 0
(-2150 3125);
DISPLAY 0.617021 (-2150 3125);
PAINT AQUA (-2150 3125);
DISPLAY INVISIBLE (-2150 3125);
FORCEPROP 2 LAST BOM_COST SB
J 0
(-2150 2775);
PAINT MONO (-2150 2775);
DISPLAY INVISIBLE (-2150 2775);
FORCEPROP 2 LAST CDS_LIB dev_discrete
J 0
(-2200 3025);
PAINT ORANGE (-2200 3025);
DISPLAY INVISIBLE (-2200 3025);
FORCEPROP 2 LAST CDS_SEC 1
J 0
(-2150 3225);
DISPLAY 1.361702 (-2150 3225);
PAINT ORANGE (-2150 3225);
DISPLAY INVISIBLE (-2150 3225);
FORCEPROP 2 LAST $SEC 1
J 0
(-2150 3225);
DISPLAY 0.914894 (-2150 3225);
PAINT MONO (-2150 3225);
DISPLAY INVISIBLE (-2150 3225);
FORCEPROP 1 LAST PATH I44
J 0
(-2150 3175);
DISPLAY 0.978723 (-2150 3175);
PAINT WHITE (-2150 3175);
DISPLAY INVISIBLE (-2150 3175);
FORCEPROP 2 LAST ROOM SB_DECOUPLING
J 0
(-2200 3025);
PAINT WHITE (-2200 3025);
DISPLAY INVISIBLE (-2200 3025);
FORCEADD CAP_A..1
(-2600 3025);
FORCEPROP 1 LAST LOCATION C3N17
J 0
(-2550 3125);
DISPLAY 0.617021 (-2550 3125);
PAINT AQUA (-2550 3125);
FORCEPROP 1 LAST PART_NUMBER D97712-004
J 0
(-2550 2875);
DISPLAY 0.617021 (-2550 2875);
PAINT BLUE (-2550 2875);
FORCEPROP 1 LAST VALUE 1.0UF
J 0
(-2550 3075);
DISPLAY 0.617021 (-2550 3075);
PAINT SKYBLUE (-2550 3075);
FORCEPROP 1 LAST TOLERANCE 10%
J 0
(-2550 2975);
DISPLAY 0.617021 (-2550 2975);
PAINT SKYBLUE (-2550 2975);
FORCEPROP 1 LAST PACK_TYPE 0402V
J 0
(-2550 2825);
DISPLAY 0.617021 (-2550 2825);
PAINT SKYBLUE (-2550 2825);
FORCEPROP 1 LAST VOLTAGE 6.3V
J 0
(-2550 3025);
DISPLAY 0.617021 (-2550 3025);
PAINT SKYBLUE (-2550 3025);
FORCEPROP 1 LAST MATERIAL X6S
J 0
(-2550 2925);
DISPLAY 0.617021 (-2550 2925);
PAINT SKYBLUE (-2550 2925);
FORCEPROP 1 LASTPIN (-2600 3125) $PN 1
J 0
(-2590 3105);
DISPLAY 0.617021 (-2590 3105);
PAINT WHITE (-2590 3105);
FORCEPROP 1 LASTPIN (-2600 2925) $PN 2
J 0
(-2590 2905);
DISPLAY 0.617021 (-2590 2905);
PAINT WHITE (-2590 2905);
FORCEPROP 2 LAST CDS_LOCATION C3N17
J 0
(-2550 3125);
DISPLAY 0.617021 (-2550 3125);
PAINT AQUA (-2550 3125);
DISPLAY INVISIBLE (-2550 3125);
FORCEPROP 2 LAST BOM_COST SB
J 0
(-2550 2775);
PAINT MONO (-2550 2775);
DISPLAY INVISIBLE (-2550 2775);
FORCEPROP 2 LAST CDS_LIB dev_discrete
J 0
(-2600 3025);
PAINT ORANGE (-2600 3025);
DISPLAY INVISIBLE (-2600 3025);
FORCEPROP 2 LAST CDS_SEC 1
J 0
(-2550 3225);
DISPLAY 1.361702 (-2550 3225);
PAINT ORANGE (-2550 3225);
DISPLAY INVISIBLE (-2550 3225);
FORCEPROP 2 LAST $SEC 1
J 0
(-2550 3225);
DISPLAY 0.914894 (-2550 3225);
PAINT MONO (-2550 3225);
DISPLAY INVISIBLE (-2550 3225);
FORCEPROP 1 LAST PATH I45
J 0
(-2550 3175);
DISPLAY 0.978723 (-2550 3175);
PAINT WHITE (-2550 3175);
DISPLAY INVISIBLE (-2550 3175);
FORCEPROP 2 LAST ROOM SB_DECOUPLING
J 0
(-2600 3025);
PAINT WHITE (-2600 3025);
DISPLAY INVISIBLE (-2600 3025);
FORCEADD CAP_A..1
(-3000 4050);
FORCEPROP 1 LAST LOCATION C3N4
J 0
(-2950 4150);
DISPLAY 0.617021 (-2950 4150);
PAINT AQUA (-2950 4150);
FORCEPROP 1 LAST PART_NUMBER D97712-004
J 0
(-2950 3900);
DISPLAY 0.617021 (-2950 3900);
PAINT BLUE (-2950 3900);
FORCEPROP 1 LAST VALUE 1.0UF
J 0
(-2950 4100);
DISPLAY 0.617021 (-2950 4100);
PAINT SKYBLUE (-2950 4100);
FORCEPROP 1 LAST TOLERANCE 10%
J 0
(-2950 4000);
DISPLAY 0.617021 (-2950 4000);
PAINT SKYBLUE (-2950 4000);
FORCEPROP 1 LAST PACK_TYPE 0402V
J 0
(-2950 3850);
DISPLAY 0.617021 (-2950 3850);
PAINT SKYBLUE (-2950 3850);
FORCEPROP 1 LAST VOLTAGE 6.3V
J 0
(-2950 4050);
DISPLAY 0.617021 (-2950 4050);
PAINT SKYBLUE (-2950 4050);
FORCEPROP 1 LAST MATERIAL X6S
J 0
(-2950 3950);
DISPLAY 0.617021 (-2950 3950);
PAINT SKYBLUE (-2950 3950);
FORCEPROP 1 LASTPIN (-3000 4150) $PN 1
J 0
(-2990 4130);
DISPLAY 0.617021 (-2990 4130);
PAINT WHITE (-2990 4130);
FORCEPROP 1 LASTPIN (-3000 3950) $PN 2
J 0
(-2990 3930);
DISPLAY 0.617021 (-2990 3930);
PAINT WHITE (-2990 3930);
FORCEPROP 2 LAST CDS_LOCATION C3N4
J 0
(-2950 4150);
DISPLAY 0.617021 (-2950 4150);
PAINT AQUA (-2950 4150);
DISPLAY INVISIBLE (-2950 4150);
FORCEPROP 2 LAST BOM_COST SB
J 0
(-2950 3800);
PAINT MONO (-2950 3800);
DISPLAY INVISIBLE (-2950 3800);
FORCEPROP 2 LAST CDS_LIB dev_discrete
J 0
(-3000 4050);
PAINT ORANGE (-3000 4050);
DISPLAY INVISIBLE (-3000 4050);
FORCEPROP 2 LAST CDS_SEC 1
J 0
(-2950 4250);
DISPLAY 1.361702 (-2950 4250);
PAINT ORANGE (-2950 4250);
DISPLAY INVISIBLE (-2950 4250);
FORCEPROP 2 LAST $SEC 1
J 0
(-2950 4250);
DISPLAY 0.914894 (-2950 4250);
PAINT MONO (-2950 4250);
DISPLAY INVISIBLE (-2950 4250);
FORCEPROP 1 LAST PATH I46
J 0
(-2950 4200);
DISPLAY 0.978723 (-2950 4200);
PAINT WHITE (-2950 4200);
DISPLAY INVISIBLE (-2950 4200);
FORCEPROP 2 LAST ROOM SB_DECOUPLING
J 0
(-3000 4050);
PAINT WHITE (-3000 4050);
DISPLAY INVISIBLE (-3000 4050);
FORCEADD PVNN_PCH_STBY..1
(-3225 4300);
FORCEPROP 3 LASTPIN (-3225 4250) SIG_NAME PVNN_PCH_STBY\g
J 0
(-3215 4260);
DISPLAY 0.659574 (-3215 4260);
PAINT MONO (-3215 4260);
DISPLAY INVISIBLE (-3215 4260);
FORCEPROP 1 LAST VOLTAGE 1.0V
J 0
(-3270 4257);
DISPLAY 0.340426 (-3270 4257);
PAINT SKYBLUE (-3270 4257);
DISPLAY INVISIBLE (-3270 4257);
FORCEPROP 2 LAST CDS_LIB mstr_symbols
J 0
(-3225 4300);
PAINT ORANGE (-3225 4300);
DISPLAY INVISIBLE (-3225 4300);
FORCEPROP 2 LAST BOM_COST SB
J 0
(-3225 4450);
PAINT MONO (-3225 4450);
DISPLAY INVISIBLE (-3225 4450);
FORCEPROP 1 LAST BODY_TYPE PLUMBING
J 0
(-3270 4257);
DISPLAY 0.340426 (-3270 4257);
PAINT GREEN (-3270 4257);
DISPLAY INVISIBLE (-3270 4257);
FORCEPROP 1 LAST PATH I47
J 0
(-3175 4325);
DISPLAY 0.872340 (-3175 4325);
PAINT AQUA (-3175 4325);
DISPLAY INVISIBLE (-3175 4325);
FORCEPROP 2 LAST ROOM SB_DECOUPLING
J 0
(-3225 4400);
DISPLAY 1.361702 (-3225 4400);
PAINT WHITE (-3225 4400);
DISPLAY INVISIBLE (-3225 4400);
FORCEPROP 1 LAST HDL_POWER PVNN_PCH_STBY
J 1
(-3225 4350);
DISPLAY 0.872340 (-3225 4350);
PAINT GREEN (-3225 4350);
DISPLAY INVISIBLE (-3225 4350);
FORCEADD CAP_A..1
(-3400 4050);
FORCEPROP 1 LAST LOCATION C3N5
J 0
(-3350 4150);
DISPLAY 0.617021 (-3350 4150);
PAINT AQUA (-3350 4150);
FORCEPROP 1 LAST PART_NUMBER D97712-004
J 0
(-3350 3900);
DISPLAY 0.617021 (-3350 3900);
PAINT BLUE (-3350 3900);
FORCEPROP 1 LAST VALUE 1.0UF
J 0
(-3350 4100);
DISPLAY 0.617021 (-3350 4100);
PAINT SKYBLUE (-3350 4100);
FORCEPROP 1 LAST TOLERANCE 10%
J 0
(-3350 4000);
DISPLAY 0.617021 (-3350 4000);
PAINT SKYBLUE (-3350 4000);
FORCEPROP 1 LAST PACK_TYPE 0402V
J 0
(-3350 3850);
DISPLAY 0.617021 (-3350 3850);
PAINT SKYBLUE (-3350 3850);
FORCEPROP 1 LAST VOLTAGE 6.3V
J 0
(-3350 4050);
DISPLAY 0.617021 (-3350 4050);
PAINT SKYBLUE (-3350 4050);
FORCEPROP 1 LAST MATERIAL X6S
J 0
(-3350 3950);
DISPLAY 0.617021 (-3350 3950);
PAINT SKYBLUE (-3350 3950);
FORCEPROP 1 LASTPIN (-3400 4150) $PN 1
J 0
(-3390 4130);
DISPLAY 0.617021 (-3390 4130);
PAINT WHITE (-3390 4130);
FORCEPROP 1 LASTPIN (-3400 3950) $PN 2
J 0
(-3390 3930);
DISPLAY 0.617021 (-3390 3930);
PAINT WHITE (-3390 3930);
FORCEPROP 2 LAST CDS_LOCATION C3N5
J 0
(-3350 4150);
DISPLAY 0.617021 (-3350 4150);
PAINT AQUA (-3350 4150);
DISPLAY INVISIBLE (-3350 4150);
FORCEPROP 2 LAST BOM_COST SB
J 0
(-3350 3800);
PAINT MONO (-3350 3800);
DISPLAY INVISIBLE (-3350 3800);
FORCEPROP 2 LAST CDS_LIB dev_discrete
J 0
(-3400 4050);
PAINT ORANGE (-3400 4050);
DISPLAY INVISIBLE (-3400 4050);
FORCEPROP 2 LAST CDS_SEC 1
J 0
(-3350 4250);
DISPLAY 1.361702 (-3350 4250);
PAINT ORANGE (-3350 4250);
DISPLAY INVISIBLE (-3350 4250);
FORCEPROP 2 LAST $SEC 1
J 0
(-3350 4250);
DISPLAY 0.914894 (-3350 4250);
PAINT MONO (-3350 4250);
DISPLAY INVISIBLE (-3350 4250);
FORCEPROP 1 LAST PATH I48
J 0
(-3350 4200);
DISPLAY 0.978723 (-3350 4200);
PAINT WHITE (-3350 4200);
DISPLAY INVISIBLE (-3350 4200);
FORCEPROP 2 LAST ROOM SB_DECOUPLING
J 0
(-3400 4050);
PAINT WHITE (-3400 4050);
DISPLAY INVISIBLE (-3400 4050);
FORCEADD CAP_A..1
(-2975 3025);
FORCEPROP 1 LAST LOCATION C3N15
J 0
(-2925 3125);
DISPLAY 0.617021 (-2925 3125);
PAINT AQUA (-2925 3125);
FORCEPROP 1 LAST PART_NUMBER D97712-004
J 0
(-2925 2875);
DISPLAY 0.617021 (-2925 2875);
PAINT BLUE (-2925 2875);
FORCEPROP 1 LAST VALUE 1.0UF
J 0
(-2925 3075);
DISPLAY 0.617021 (-2925 3075);
PAINT SKYBLUE (-2925 3075);
FORCEPROP 1 LAST TOLERANCE 10%
J 0
(-2925 2975);
DISPLAY 0.617021 (-2925 2975);
PAINT SKYBLUE (-2925 2975);
FORCEPROP 1 LAST PACK_TYPE 0402V
J 0
(-2925 2825);
DISPLAY 0.617021 (-2925 2825);
PAINT SKYBLUE (-2925 2825);
FORCEPROP 1 LAST VOLTAGE 6.3V
J 0
(-2925 3025);
DISPLAY 0.617021 (-2925 3025);
PAINT SKYBLUE (-2925 3025);
FORCEPROP 1 LAST MATERIAL X6S
J 0
(-2925 2925);
DISPLAY 0.617021 (-2925 2925);
PAINT SKYBLUE (-2925 2925);
FORCEPROP 1 LASTPIN (-2975 3125) $PN 1
J 0
(-2965 3105);
DISPLAY 0.617021 (-2965 3105);
PAINT WHITE (-2965 3105);
FORCEPROP 1 LASTPIN (-2975 2925) $PN 2
J 0
(-2965 2905);
DISPLAY 0.617021 (-2965 2905);
PAINT WHITE (-2965 2905);
FORCEPROP 2 LAST CDS_LOCATION C3N15
J 0
(-2925 3125);
DISPLAY 0.617021 (-2925 3125);
PAINT AQUA (-2925 3125);
DISPLAY INVISIBLE (-2925 3125);
FORCEPROP 2 LAST BOM_COST SB
J 0
(-2925 2775);
PAINT MONO (-2925 2775);
DISPLAY INVISIBLE (-2925 2775);
FORCEPROP 2 LAST CDS_LIB dev_discrete
J 0
(-2975 3025);
PAINT ORANGE (-2975 3025);
DISPLAY INVISIBLE (-2975 3025);
FORCEPROP 2 LAST CDS_SEC 1
J 0
(-2925 3225);
DISPLAY 1.361702 (-2925 3225);
PAINT ORANGE (-2925 3225);
DISPLAY INVISIBLE (-2925 3225);
FORCEPROP 2 LAST $SEC 1
J 0
(-2925 3225);
DISPLAY 0.914894 (-2925 3225);
PAINT MONO (-2925 3225);
DISPLAY INVISIBLE (-2925 3225);
FORCEPROP 1 LAST PATH I49
J 0
(-2925 3175);
DISPLAY 0.978723 (-2925 3175);
PAINT WHITE (-2925 3175);
DISPLAY INVISIBLE (-2925 3175);
FORCEPROP 2 LAST ROOM SB_DECOUPLING
J 0
(-2975 3025);
PAINT WHITE (-2975 3025);
DISPLAY INVISIBLE (-2975 3025);
FORCEADD PVNN_PCH_STBY..1
(1350 4725);
FORCEPROP 3 LASTPIN (1350 4675) SIG_NAME PVNN_PCH_STBY\g
J 0
(1360 4685);
DISPLAY 0.659574 (1360 4685);
PAINT MONO (1360 4685);
DISPLAY INVISIBLE (1360 4685);
FORCEPROP 1 LAST VOLTAGE 1.0V
J 0
(1305 4682);
DISPLAY 0.340426 (1305 4682);
PAINT SKYBLUE (1305 4682);
DISPLAY INVISIBLE (1305 4682);
FORCEPROP 2 LAST CDS_LIB mstr_symbols
J 0
(1350 4725);
PAINT ORANGE (1350 4725);
DISPLAY INVISIBLE (1350 4725);
FORCEPROP 2 LAST BOM_COST SB
J 0
(1350 4825);
DISPLAY 1.361702 (1350 4825);
PAINT ORANGE (1350 4825);
DISPLAY INVISIBLE (1350 4825);
FORCEPROP 1 LAST BODY_TYPE PLUMBING
J 0
(1305 4682);
DISPLAY 0.340426 (1305 4682);
PAINT GREEN (1305 4682);
DISPLAY INVISIBLE (1305 4682);
FORCEPROP 1 LAST PATH I5
J 0
(1400 4750);
DISPLAY 0.872340 (1400 4750);
PAINT AQUA (1400 4750);
DISPLAY INVISIBLE (1400 4750);
FORCEPROP 2 LAST ROOM SB_DECOUPLING
J 0
(1350 4825);
DISPLAY 1.361702 (1350 4825);
PAINT ORANGE (1350 4825);
DISPLAY INVISIBLE (1350 4825);
FORCEPROP 1 LAST HDL_POWER PVNN_PCH_STBY
J 1
(1350 4775);
DISPLAY 0.872340 (1350 4775);
PAINT GREEN (1350 4775);
DISPLAY INVISIBLE (1350 4775);
FORCEADD PVNN_PCH_STBY..1
(-3200 3275);
FORCEPROP 3 LASTPIN (-3200 3225) SIG_NAME PVNN_PCH_STBY\g
J 0
(-3190 3235);
DISPLAY 0.659574 (-3190 3235);
PAINT MONO (-3190 3235);
DISPLAY INVISIBLE (-3190 3235);
FORCEPROP 1 LAST VOLTAGE 1.0V
J 0
(-3245 3232);
DISPLAY 0.340426 (-3245 3232);
PAINT SKYBLUE (-3245 3232);
DISPLAY INVISIBLE (-3245 3232);
FORCEPROP 2 LAST CDS_LIB mstr_symbols
J 0
(-3200 3275);
PAINT ORANGE (-3200 3275);
DISPLAY INVISIBLE (-3200 3275);
FORCEPROP 2 LAST BOM_COST SB
J 0
(-3200 3425);
PAINT MONO (-3200 3425);
DISPLAY INVISIBLE (-3200 3425);
FORCEPROP 1 LAST BODY_TYPE PLUMBING
J 0
(-3245 3232);
DISPLAY 0.340426 (-3245 3232);
PAINT GREEN (-3245 3232);
DISPLAY INVISIBLE (-3245 3232);
FORCEPROP 1 LAST PATH I50
J 0
(-3150 3300);
DISPLAY 0.872340 (-3150 3300);
PAINT AQUA (-3150 3300);
DISPLAY INVISIBLE (-3150 3300);
FORCEPROP 2 LAST ROOM SB_DECOUPLING
J 0
(-3200 3375);
DISPLAY 1.361702 (-3200 3375);
PAINT WHITE (-3200 3375);
DISPLAY INVISIBLE (-3200 3375);
FORCEPROP 1 LAST HDL_POWER PVNN_PCH_STBY
J 1
(-3200 3325);
DISPLAY 0.872340 (-3200 3325);
PAINT GREEN (-3200 3325);
DISPLAY INVISIBLE (-3200 3325);
FORCEADD CAP_A..1
(-3375 3025);
FORCEPROP 1 LAST LOCATION C3N20
J 0
(-3325 3125);
DISPLAY 0.617021 (-3325 3125);
PAINT AQUA (-3325 3125);
FORCEPROP 1 LAST PART_NUMBER D97712-004
J 0
(-3325 2875);
DISPLAY 0.617021 (-3325 2875);
PAINT BLUE (-3325 2875);
FORCEPROP 1 LAST VALUE 1.0UF
J 0
(-3325 3075);
DISPLAY 0.617021 (-3325 3075);
PAINT SKYBLUE (-3325 3075);
FORCEPROP 1 LAST TOLERANCE 10%
J 0
(-3325 2975);
DISPLAY 0.617021 (-3325 2975);
PAINT SKYBLUE (-3325 2975);
FORCEPROP 1 LAST PACK_TYPE 0402V
J 0
(-3325 2825);
DISPLAY 0.617021 (-3325 2825);
PAINT SKYBLUE (-3325 2825);
FORCEPROP 1 LAST VOLTAGE 6.3V
J 0
(-3325 3025);
DISPLAY 0.617021 (-3325 3025);
PAINT SKYBLUE (-3325 3025);
FORCEPROP 1 LAST MATERIAL X6S
J 0
(-3325 2925);
DISPLAY 0.617021 (-3325 2925);
PAINT SKYBLUE (-3325 2925);
FORCEPROP 1 LASTPIN (-3375 3125) $PN 1
J 0
(-3365 3105);
DISPLAY 0.617021 (-3365 3105);
PAINT WHITE (-3365 3105);
FORCEPROP 1 LASTPIN (-3375 2925) $PN 2
J 0
(-3365 2905);
DISPLAY 0.617021 (-3365 2905);
PAINT WHITE (-3365 2905);
FORCEPROP 2 LAST CDS_LOCATION C3N20
J 0
(-3325 3125);
DISPLAY 0.617021 (-3325 3125);
PAINT AQUA (-3325 3125);
DISPLAY INVISIBLE (-3325 3125);
FORCEPROP 2 LAST BOM_COST SB
J 0
(-3325 2775);
PAINT MONO (-3325 2775);
DISPLAY INVISIBLE (-3325 2775);
FORCEPROP 2 LAST CDS_LIB dev_discrete
J 0
(-3375 3025);
PAINT ORANGE (-3375 3025);
DISPLAY INVISIBLE (-3375 3025);
FORCEPROP 2 LAST CDS_SEC 1
J 0
(-3325 3225);
DISPLAY 1.361702 (-3325 3225);
PAINT ORANGE (-3325 3225);
DISPLAY INVISIBLE (-3325 3225);
FORCEPROP 2 LAST $SEC 1
J 0
(-3325 3225);
DISPLAY 0.914894 (-3325 3225);
PAINT MONO (-3325 3225);
DISPLAY INVISIBLE (-3325 3225);
FORCEPROP 1 LAST PATH I51
J 0
(-3325 3175);
DISPLAY 0.978723 (-3325 3175);
PAINT WHITE (-3325 3175);
DISPLAY INVISIBLE (-3325 3175);
FORCEPROP 2 LAST ROOM SB_DECOUPLING
J 0
(-3375 3025);
PAINT WHITE (-3375 3025);
DISPLAY INVISIBLE (-3375 3025);
FORCEADD CAP_A..1
(-2550 1925);
FORCEPROP 1 LAST LOCATION C3L23
J 0
(-2500 2025);
DISPLAY 0.617021 (-2500 2025);
PAINT AQUA (-2500 2025);
FORCEPROP 1 LAST PART_NUMBER E15431-004
J 0
(-2500 1775);
DISPLAY 0.617021 (-2500 1775);
PAINT BLUE (-2500 1775);
FORCEPROP 1 LAST VALUE 22.0UF
J 0
(-2500 1975);
DISPLAY 0.617021 (-2500 1975);
PAINT SKYBLUE (-2500 1975);
FORCEPROP 1 LAST TOLERANCE 20%
J 0
(-2500 1875);
DISPLAY 0.617021 (-2500 1875);
PAINT SKYBLUE (-2500 1875);
FORCEPROP 1 LAST PACK_TYPE 0603V
J 0
(-2500 1725);
DISPLAY 0.617021 (-2500 1725);
PAINT SKYBLUE (-2500 1725);
FORCEPROP 1 LAST VOLTAGE 4V
J 0
(-2500 1925);
DISPLAY 0.617021 (-2500 1925);
PAINT SKYBLUE (-2500 1925);
FORCEPROP 1 LAST MATERIAL X6S
J 0
(-2500 1825);
DISPLAY 0.617021 (-2500 1825);
PAINT SKYBLUE (-2500 1825);
FORCEPROP 1 LASTPIN (-2550 2025) $PN 1
J 0
(-2540 2005);
DISPLAY 0.617021 (-2540 2005);
PAINT ORANGE (-2540 2005);
FORCEPROP 1 LASTPIN (-2550 1825) $PN 2
J 0
(-2540 1805);
DISPLAY 0.617021 (-2540 1805);
PAINT ORANGE (-2540 1805);
FORCEPROP 2 LAST CDS_LOCATION C3L23
J 0
(-2500 2025);
DISPLAY 0.617021 (-2500 2025);
PAINT AQUA (-2500 2025);
DISPLAY INVISIBLE (-2500 2025);
FORCEPROP 2 LAST BOM_COST SB
J 0
(-2500 2125);
DISPLAY 1.361702 (-2500 2125);
PAINT ORANGE (-2500 2125);
DISPLAY INVISIBLE (-2500 2125);
FORCEPROP 2 LAST CDS_LIB dev_discrete
J 0
(-2550 1925);
PAINT ORANGE (-2550 1925);
DISPLAY INVISIBLE (-2550 1925);
FORCEPROP 2 LAST CDS_SEC 1
J 0
(-2500 2125);
PAINT MONO (-2500 2125);
DISPLAY INVISIBLE (-2500 2125);
FORCEPROP 2 LAST $SEC 1
J 0
(-2500 2125);
PAINT MONO (-2500 2125);
DISPLAY INVISIBLE (-2500 2125);
FORCEPROP 1 LAST PATH I52
J 0
(-2500 2075);
DISPLAY 0.978723 (-2500 2075);
PAINT WHITE (-2500 2075);
DISPLAY INVISIBLE (-2500 2075);
FORCEPROP 2 LAST ROOM SB_DECOUPLING
J 0
(-2500 2075);
DISPLAY 1.361702 (-2500 2075);
PAINT ORANGE (-2500 2075);
DISPLAY INVISIBLE (-2500 2075);
FORCEADD PVNN_PCH_STBY..1
(-3150 2200);
FORCEPROP 3 LASTPIN (-3150 2150) SIG_NAME PVNN_PCH_STBY\g
J 0
(-3140 2160);
DISPLAY 0.659574 (-3140 2160);
PAINT MONO (-3140 2160);
DISPLAY INVISIBLE (-3140 2160);
FORCEPROP 1 LAST VOLTAGE 1.0V
J 0
(-3195 2157);
DISPLAY 0.340426 (-3195 2157);
PAINT SKYBLUE (-3195 2157);
DISPLAY INVISIBLE (-3195 2157);
FORCEPROP 2 LAST CDS_LIB mstr_symbols
J 0
(-3150 2200);
PAINT ORANGE (-3150 2200);
DISPLAY INVISIBLE (-3150 2200);
FORCEPROP 2 LAST BOM_COST SB
J 0
(-3150 2300);
DISPLAY 1.361702 (-3150 2300);
PAINT ORANGE (-3150 2300);
DISPLAY INVISIBLE (-3150 2300);
FORCEPROP 1 LAST BODY_TYPE PLUMBING
J 0
(-3195 2157);
DISPLAY 0.340426 (-3195 2157);
PAINT GREEN (-3195 2157);
DISPLAY INVISIBLE (-3195 2157);
FORCEPROP 1 LAST PATH I53
J 0
(-3100 2225);
DISPLAY 0.872340 (-3100 2225);
PAINT AQUA (-3100 2225);
DISPLAY INVISIBLE (-3100 2225);
FORCEPROP 2 LAST ROOM SB_DECOUPLING
J 0
(-3150 2300);
DISPLAY 1.361702 (-3150 2300);
PAINT ORANGE (-3150 2300);
DISPLAY INVISIBLE (-3150 2300);
FORCEPROP 1 LAST HDL_POWER PVNN_PCH_STBY
J 1
(-3150 2250);
DISPLAY 0.872340 (-3150 2250);
PAINT GREEN (-3150 2250);
DISPLAY INVISIBLE (-3150 2250);
FORCEADD CAP_A..1
(-2950 1925);
FORCEPROP 1 LAST LOCATION C3L22
J 0
(-2900 2025);
DISPLAY 0.617021 (-2900 2025);
PAINT AQUA (-2900 2025);
FORCEPROP 1 LAST PART_NUMBER E15431-004
J 0
(-2900 1775);
DISPLAY 0.617021 (-2900 1775);
PAINT BLUE (-2900 1775);
FORCEPROP 1 LAST VALUE 22.0UF
J 0
(-2900 1975);
DISPLAY 0.617021 (-2900 1975);
PAINT SKYBLUE (-2900 1975);
FORCEPROP 1 LAST TOLERANCE 20%
J 0
(-2900 1875);
DISPLAY 0.617021 (-2900 1875);
PAINT SKYBLUE (-2900 1875);
FORCEPROP 1 LAST PACK_TYPE 0603V
J 0
(-2900 1725);
DISPLAY 0.617021 (-2900 1725);
PAINT SKYBLUE (-2900 1725);
FORCEPROP 1 LAST VOLTAGE 4V
J 0
(-2900 1925);
DISPLAY 0.617021 (-2900 1925);
PAINT SKYBLUE (-2900 1925);
FORCEPROP 1 LAST MATERIAL X6S
J 0
(-2900 1825);
DISPLAY 0.617021 (-2900 1825);
PAINT SKYBLUE (-2900 1825);
FORCEPROP 1 LASTPIN (-2950 2025) $PN 1
J 0
(-2940 2005);
DISPLAY 0.617021 (-2940 2005);
PAINT WHITE (-2940 2005);
FORCEPROP 1 LASTPIN (-2950 1825) $PN 2
J 0
(-2940 1805);
DISPLAY 0.617021 (-2940 1805);
PAINT WHITE (-2940 1805);
FORCEPROP 2 LAST CDS_LOCATION C3L22
J 0
(-2900 2025);
DISPLAY 0.617021 (-2900 2025);
PAINT AQUA (-2900 2025);
DISPLAY INVISIBLE (-2900 2025);
FORCEPROP 2 LAST BOM_COST SB
J 0
(-2900 2125);
DISPLAY 1.361702 (-2900 2125);
PAINT ORANGE (-2900 2125);
DISPLAY INVISIBLE (-2900 2125);
FORCEPROP 2 LAST CDS_LIB dev_discrete
J 0
(-2950 1925);
PAINT ORANGE (-2950 1925);
DISPLAY INVISIBLE (-2950 1925);
FORCEPROP 2 LAST CDS_SEC 1
J 0
(-2900 2125);
DISPLAY 1.361702 (-2900 2125);
PAINT ORANGE (-2900 2125);
DISPLAY INVISIBLE (-2900 2125);
FORCEPROP 2 LAST $SEC 1
J 0
(-2900 2125);
DISPLAY 0.914894 (-2900 2125);
PAINT MONO (-2900 2125);
DISPLAY INVISIBLE (-2900 2125);
FORCEPROP 1 LAST PATH I54
J 0
(-2900 2075);
DISPLAY 0.978723 (-2900 2075);
PAINT WHITE (-2900 2075);
DISPLAY INVISIBLE (-2900 2075);
FORCEPROP 2 LAST ROOM SB_DECOUPLING
J 0
(-2900 2075);
DISPLAY 1.361702 (-2900 2075);
PAINT ORANGE (-2900 2075);
DISPLAY INVISIBLE (-2900 2075);
FORCEADD GND..1
(-3100 1600);
FORCEPROP 3 LASTPIN (-3100 1650) SIG_NAME GND\g
J 0
(-3090 1660);
DISPLAY 0.659574 (-3090 1660);
PAINT MONO (-3090 1660);
DISPLAY INVISIBLE (-3090 1660);
FORCEPROP 1 LAST VOLTAGE 0.0V
J 0
(-3145 1557);
DISPLAY 0.340426 (-3145 1557);
PAINT SKYBLUE (-3145 1557);
DISPLAY INVISIBLE (-3145 1557);
FORCEPROP 2 LAST CDS_LIB mstr_symbols
J 0
(-3100 1600);
PAINT MONO (-3100 1600);
DISPLAY INVISIBLE (-3100 1600);
FORCEPROP 1 LAST SIZE 1B
J 0
(-3025 1550);
DISPLAY 1.170213 (-3025 1550);
PAINT AQUA (-3025 1550);
DISPLAY INVISIBLE (-3025 1550);
FORCEPROP 2 LAST BOM_COST SB
J 0
(-3075 1675);
DISPLAY 1.361702 (-3075 1675);
PAINT ORANGE (-3075 1675);
DISPLAY INVISIBLE (-3075 1675);
FORCEPROP 1 LAST BODY_TYPE PLUMBING
J 0
(-3145 1557);
DISPLAY 0.340426 (-3145 1557);
PAINT GREEN (-3145 1557);
DISPLAY INVISIBLE (-3145 1557);
FORCEPROP 1 LAST PATH I55
J 0
(-3025 1600);
DISPLAY 0.872340 (-3025 1600);
PAINT AQUA (-3025 1600);
DISPLAY INVISIBLE (-3025 1600);
FORCEPROP 2 LAST ROOM SB_DECOUPLING
J 0
(-3075 1675);
DISPLAY 1.361702 (-3075 1675);
PAINT ORANGE (-3075 1675);
DISPLAY INVISIBLE (-3075 1675);
FORCEPROP 1 LAST HDL_POWER GND
J 0
(-3100 1750);
DISPLAY 1.170213 (-3100 1750);
PAINT GREEN (-3100 1750);
DISPLAY INVISIBLE (-3100 1750);
FORCEADD CAP_A..1
(-3425 1925);
FORCEPROP 1 LAST LOCATION C3L24
J 0
(-3375 2025);
DISPLAY 0.617021 (-3375 2025);
PAINT AQUA (-3375 2025);
FORCEPROP 1 LAST PART_NUMBER E15431-004
J 0
(-3375 1775);
DISPLAY 0.617021 (-3375 1775);
PAINT BLUE (-3375 1775);
FORCEPROP 1 LAST VALUE 22.0UF
J 0
(-3375 1975);
DISPLAY 0.617021 (-3375 1975);
PAINT SKYBLUE (-3375 1975);
FORCEPROP 1 LAST TOLERANCE 20%
J 0
(-3375 1875);
DISPLAY 0.617021 (-3375 1875);
PAINT SKYBLUE (-3375 1875);
FORCEPROP 1 LAST PACK_TYPE 0603V
J 0
(-3375 1725);
DISPLAY 0.617021 (-3375 1725);
PAINT SKYBLUE (-3375 1725);
FORCEPROP 1 LAST VOLTAGE 4V
J 0
(-3375 1925);
DISPLAY 0.617021 (-3375 1925);
PAINT SKYBLUE (-3375 1925);
FORCEPROP 1 LAST MATERIAL X6S
J 0
(-3375 1825);
DISPLAY 0.617021 (-3375 1825);
PAINT SKYBLUE (-3375 1825);
FORCEPROP 1 LASTPIN (-3425 2025) $PN 1
J 0
(-3415 2005);
DISPLAY 0.617021 (-3415 2005);
PAINT WHITE (-3415 2005);
FORCEPROP 1 LASTPIN (-3425 1825) $PN 2
J 0
(-3415 1805);
DISPLAY 0.617021 (-3415 1805);
PAINT WHITE (-3415 1805);
FORCEPROP 2 LAST CDS_LOCATION C3L24
J 0
(-3375 2025);
DISPLAY 0.617021 (-3375 2025);
PAINT AQUA (-3375 2025);
DISPLAY INVISIBLE (-3375 2025);
FORCEPROP 2 LAST BOM_COST SB
J 0
(-3375 2125);
DISPLAY 1.361702 (-3375 2125);
PAINT ORANGE (-3375 2125);
DISPLAY INVISIBLE (-3375 2125);
FORCEPROP 2 LAST CDS_LIB dev_discrete
J 0
(-3425 1925);
PAINT ORANGE (-3425 1925);
DISPLAY INVISIBLE (-3425 1925);
FORCEPROP 2 LAST CDS_SEC 1
J 0
(-3375 2125);
DISPLAY 1.361702 (-3375 2125);
PAINT ORANGE (-3375 2125);
DISPLAY INVISIBLE (-3375 2125);
FORCEPROP 2 LAST $SEC 1
J 0
(-3375 2125);
DISPLAY 0.914894 (-3375 2125);
PAINT MONO (-3375 2125);
DISPLAY INVISIBLE (-3375 2125);
FORCEPROP 1 LAST PATH I56
J 0
(-3375 2075);
DISPLAY 0.978723 (-3375 2075);
PAINT WHITE (-3375 2075);
DISPLAY INVISIBLE (-3375 2075);
FORCEPROP 2 LAST ROOM SB_DECOUPLING
J 0
(-3375 2075);
DISPLAY 1.361702 (-3375 2075);
PAINT ORANGE (-3375 2075);
DISPLAY INVISIBLE (-3375 2075);
FORCEADD CAP_A..1
(1075 4475);
FORCEPROP 1 LAST LOCATION C3M6
J 0
(1125 4575);
DISPLAY 0.617021 (1125 4575);
PAINT AQUA (1125 4575);
FORCEPROP 1 LAST PART_NUMBER E15431-004
J 0
(1125 4325);
DISPLAY 0.617021 (1125 4325);
PAINT BLUE (1125 4325);
FORCEPROP 1 LAST VALUE 22.0UF
J 0
(1125 4525);
DISPLAY 0.617021 (1125 4525);
PAINT SKYBLUE (1125 4525);
FORCEPROP 1 LAST TOLERANCE 20%
J 0
(1125 4425);
DISPLAY 0.617021 (1125 4425);
PAINT SKYBLUE (1125 4425);
FORCEPROP 1 LAST PACK_TYPE 0603V
J 0
(1125 4275);
DISPLAY 0.617021 (1125 4275);
PAINT SKYBLUE (1125 4275);
FORCEPROP 1 LAST VOLTAGE 4V
J 0
(1125 4475);
DISPLAY 0.617021 (1125 4475);
PAINT SKYBLUE (1125 4475);
FORCEPROP 1 LAST MATERIAL X6S
J 0
(1125 4375);
DISPLAY 0.617021 (1125 4375);
PAINT SKYBLUE (1125 4375);
FORCEPROP 1 LASTPIN (1075 4575) $PN 1
J 0
(1085 4555);
DISPLAY 0.617021 (1085 4555);
PAINT WHITE (1085 4555);
FORCEPROP 1 LASTPIN (1075 4375) $PN 2
J 0
(1085 4355);
DISPLAY 0.617021 (1085 4355);
PAINT WHITE (1085 4355);
FORCEPROP 2 LAST CDS_LOCATION C3M6
J 0
(1125 4575);
DISPLAY 0.617021 (1125 4575);
PAINT AQUA (1125 4575);
DISPLAY INVISIBLE (1125 4575);
FORCEPROP 2 LAST BOM_COST SB
J 0
(1125 4675);
DISPLAY 1.361702 (1125 4675);
PAINT ORANGE (1125 4675);
DISPLAY INVISIBLE (1125 4675);
FORCEPROP 2 LAST CDS_LIB dev_discrete
J 0
(1075 4475);
PAINT ORANGE (1075 4475);
DISPLAY INVISIBLE (1075 4475);
FORCEPROP 2 LAST CDS_SEC 1
J 0
(1125 4675);
DISPLAY 1.361702 (1125 4675);
PAINT ORANGE (1125 4675);
DISPLAY INVISIBLE (1125 4675);
FORCEPROP 2 LAST $SEC 1
J 0
(1125 4675);
DISPLAY 0.914894 (1125 4675);
PAINT MONO (1125 4675);
DISPLAY INVISIBLE (1125 4675);
FORCEPROP 1 LAST PATH I6
J 0
(1125 4625);
DISPLAY 0.978723 (1125 4625);
PAINT WHITE (1125 4625);
DISPLAY INVISIBLE (1125 4625);
FORCEPROP 2 LAST ROOM SB_DECOUPLING
J 0
(1125 4625);
DISPLAY 1.361702 (1125 4625);
PAINT ORANGE (1125 4625);
DISPLAY INVISIBLE (1125 4625);
FORCEADD CAP_A..1
(2550 3500);
FORCEPROP 1 LAST LOCATION C7C9
J 0
(2600 3600);
DISPLAY 0.617021 (2600 3600);
PAINT AQUA (2600 3600);
FORCEPROP 1 LAST PART_NUMBER E15431-004
J 0
(2600 3350);
DISPLAY 0.617021 (2600 3350);
PAINT BLUE (2600 3350);
FORCEPROP 1 LAST VALUE 22.0UF
J 0
(2600 3550);
DISPLAY 0.617021 (2600 3550);
PAINT SKYBLUE (2600 3550);
FORCEPROP 1 LAST TOLERANCE 20%
J 0
(2600 3450);
DISPLAY 0.617021 (2600 3450);
PAINT SKYBLUE (2600 3450);
FORCEPROP 1 LAST PACK_TYPE 0603V
J 0
(2600 3300);
DISPLAY 0.617021 (2600 3300);
PAINT SKYBLUE (2600 3300);
FORCEPROP 1 LAST VOLTAGE 4V
J 0
(2600 3500);
DISPLAY 0.617021 (2600 3500);
PAINT SKYBLUE (2600 3500);
FORCEPROP 1 LAST MATERIAL X6S
J 0
(2600 3400);
DISPLAY 0.617021 (2600 3400);
PAINT SKYBLUE (2600 3400);
FORCEPROP 2 LAST CDS_LOCATION C7C9
J 0
(2600 3600);
DISPLAY 0.617021 (2600 3600);
PAINT AQUA (2600 3600);
DISPLAY INVISIBLE (2600 3600);
FORCEPROP 2 LAST BOM_COST SB
J 0
(2600 3250);
PAINT MONO (2600 3250);
DISPLAY INVISIBLE (2600 3250);
FORCEPROP 2 LAST CDS_LIB dev_discrete
J 0
(2550 3500);
PAINT ORANGE (2550 3500);
DISPLAY INVISIBLE (2550 3500);
FORCEPROP 2 LAST CDS_SEC 1
J 0
(2600 3700);
DISPLAY 1.361702 (2600 3700);
PAINT ORANGE (2600 3700);
DISPLAY INVISIBLE (2600 3700);
FORCEPROP 2 LAST $SEC 1
J 0
(2600 3700);
DISPLAY 0.914894 (2600 3700);
PAINT MONO (2600 3700);
DISPLAY INVISIBLE (2600 3700);
FORCEPROP 1 LAST PATH I7
J 0
(2600 3650);
DISPLAY 0.978723 (2600 3650);
PAINT WHITE (2600 3650);
DISPLAY INVISIBLE (2600 3650);
FORCEPROP 2 LAST ROOM SB_DECOUPLING
J 0
(2550 3500);
PAINT WHITE (2550 3500);
DISPLAY INVISIBLE (2550 3500);
FORCEPROP 1 LASTPIN (2550 3600) $PN 1
J 0
(2560 3580);
DISPLAY 1.063830 (2560 3580);
PAINT WHITE (2560 3580);
DISPLAY INVISIBLE (2560 3580);
FORCEPROP 1 LASTPIN (2550 3400) $PN 2
J 0
(2560 3380);
DISPLAY 1.063830 (2560 3380);
PAINT WHITE (2560 3380);
DISPLAY INVISIBLE (2560 3380);
FORCEADD CAP_A..1
(2600 2525);
FORCEPROP 1 LAST LOCATION C3N27
J 0
(2650 2625);
DISPLAY 0.617021 (2650 2625);
PAINT AQUA (2650 2625);
FORCEPROP 1 LAST PART_NUMBER E15431-004
J 0
(2650 2375);
DISPLAY 0.617021 (2650 2375);
PAINT BLUE (2650 2375);
FORCEPROP 1 LAST VALUE 22.0UF
J 0
(2650 2575);
DISPLAY 0.617021 (2650 2575);
PAINT SKYBLUE (2650 2575);
FORCEPROP 1 LAST TOLERANCE 20%
J 0
(2650 2475);
DISPLAY 0.617021 (2650 2475);
PAINT SKYBLUE (2650 2475);
FORCEPROP 1 LAST PACK_TYPE 0603V
J 0
(2650 2325);
DISPLAY 0.617021 (2650 2325);
PAINT SKYBLUE (2650 2325);
FORCEPROP 1 LAST VOLTAGE 4V
J 0
(2650 2525);
DISPLAY 0.617021 (2650 2525);
PAINT SKYBLUE (2650 2525);
FORCEPROP 1 LAST MATERIAL X6S
J 0
(2650 2425);
DISPLAY 0.617021 (2650 2425);
PAINT SKYBLUE (2650 2425);
FORCEPROP 2 LAST CDS_LOCATION C3N27
J 0
(2650 2625);
DISPLAY 0.617021 (2650 2625);
PAINT AQUA (2650 2625);
DISPLAY INVISIBLE (2650 2625);
FORCEPROP 2 LAST BOM_COST SB
J 0
(2650 2275);
PAINT MONO (2650 2275);
DISPLAY INVISIBLE (2650 2275);
FORCEPROP 2 LAST CDS_LIB dev_discrete
J 0
(2600 2525);
PAINT ORANGE (2600 2525);
DISPLAY INVISIBLE (2600 2525);
FORCEPROP 2 LAST CDS_SEC 1
J 0
(2650 2725);
DISPLAY 1.361702 (2650 2725);
PAINT ORANGE (2650 2725);
DISPLAY INVISIBLE (2650 2725);
FORCEPROP 2 LAST $SEC 1
J 0
(2650 2725);
DISPLAY 0.914894 (2650 2725);
PAINT MONO (2650 2725);
DISPLAY INVISIBLE (2650 2725);
FORCEPROP 1 LAST PATH I8
J 0
(2650 2675);
DISPLAY 0.978723 (2650 2675);
PAINT WHITE (2650 2675);
DISPLAY INVISIBLE (2650 2675);
FORCEPROP 2 LAST ROOM SB_DECOUPLING
J 0
(2600 2525);
PAINT WHITE (2600 2525);
DISPLAY INVISIBLE (2600 2525);
FORCEPROP 1 LASTPIN (2600 2625) $PN 1
J 0
(2610 2605);
DISPLAY 1.063830 (2610 2605);
PAINT WHITE (2610 2605);
DISPLAY INVISIBLE (2610 2605);
FORCEPROP 1 LASTPIN (2600 2425) $PN 2
J 0
(2610 2405);
DISPLAY 1.063830 (2610 2405);
PAINT WHITE (2610 2405);
DISPLAY INVISIBLE (2610 2405);
FORCEADD CAP_A..1
(2225 2525);
FORCEPROP 1 LAST LOCATION C3N30
J 0
(2275 2625);
DISPLAY 0.617021 (2275 2625);
PAINT AQUA (2275 2625);
FORCEPROP 1 LAST PART_NUMBER E15431-004
J 0
(2275 2375);
DISPLAY 0.617021 (2275 2375);
PAINT BLUE (2275 2375);
FORCEPROP 1 LAST VALUE 22.0UF
J 0
(2275 2575);
DISPLAY 0.617021 (2275 2575);
PAINT SKYBLUE (2275 2575);
FORCEPROP 1 LAST TOLERANCE 20%
J 0
(2275 2475);
DISPLAY 0.617021 (2275 2475);
PAINT SKYBLUE (2275 2475);
FORCEPROP 1 LAST PACK_TYPE 0603V
J 0
(2275 2325);
DISPLAY 0.617021 (2275 2325);
PAINT SKYBLUE (2275 2325);
FORCEPROP 1 LAST VOLTAGE 4V
J 0
(2275 2525);
DISPLAY 0.617021 (2275 2525);
PAINT SKYBLUE (2275 2525);
FORCEPROP 1 LAST MATERIAL X6S
J 0
(2275 2425);
DISPLAY 0.617021 (2275 2425);
PAINT SKYBLUE (2275 2425);
FORCEPROP 2 LAST CDS_LOCATION C3N30
J 0
(2275 2625);
DISPLAY 0.617021 (2275 2625);
PAINT AQUA (2275 2625);
DISPLAY INVISIBLE (2275 2625);
FORCEPROP 2 LAST BOM_COST SB
J 0
(2275 2275);
PAINT MONO (2275 2275);
DISPLAY INVISIBLE (2275 2275);
FORCEPROP 2 LAST CDS_LIB dev_discrete
J 0
(2225 2525);
PAINT ORANGE (2225 2525);
DISPLAY INVISIBLE (2225 2525);
FORCEPROP 2 LAST CDS_SEC 1
J 0
(2275 2725);
DISPLAY 1.361702 (2275 2725);
PAINT ORANGE (2275 2725);
DISPLAY INVISIBLE (2275 2725);
FORCEPROP 2 LAST $SEC 1
J 0
(2275 2725);
DISPLAY 0.914894 (2275 2725);
PAINT MONO (2275 2725);
DISPLAY INVISIBLE (2275 2725);
FORCEPROP 1 LAST PATH I9
J 0
(2275 2675);
DISPLAY 0.978723 (2275 2675);
PAINT WHITE (2275 2675);
DISPLAY INVISIBLE (2275 2675);
FORCEPROP 2 LAST ROOM SB_DECOUPLING
J 0
(2225 2525);
PAINT WHITE (2225 2525);
DISPLAY INVISIBLE (2225 2525);
FORCEPROP 1 LASTPIN (2225 2625) $PN 1
J 0
(2235 2605);
DISPLAY 1.063830 (2235 2605);
PAINT WHITE (2235 2605);
DISPLAY INVISIBLE (2235 2605);
FORCEPROP 1 LASTPIN (2225 2425) $PN 2
J 0
(2235 2405);
DISPLAY 1.063830 (2235 2405);
PAINT WHITE (2235 2405);
DISPLAY INVISIBLE (2235 2405);
FORCEADD CAD_NOTE..1
(-1225 1225);
FORCEPROP 0 LAST L1 PLACE CAPS ON THE SECONDARY SIDE OF BGA
J 0
(-1375 1075);
DISPLAY 1.063830 (-1375 1075);
PAINT WHITE (-1375 1075);
FORCEPROP 0 LAST L2 
J 0
(-1375 1075);
DISPLAY 1.063830 (-1375 1075);
PAINT WHITE (-1375 1075);
FORCEPROP 2 LAST CDS_LIB mstr_symbols
J 0
(-1225 1225);
PAINT ORANGE (-1225 1225);
DISPLAY INVISIBLE (-1225 1225);
FORCEPROP 2 LAST BOM_COST SB
J 0
(-1375 1175);
PAINT MONO (-1375 1175);
DISPLAY INVISIBLE (-1375 1175);
FORCEPROP 1 LAST COMMENT_BODY TRUE
J 0
(-1200 1325);
DISPLAY 1.319149 (-1200 1325);
PAINT GREEN (-1200 1325);
DISPLAY INVISIBLE (-1200 1325);
FORCEPROP 2 LAST ROOM SB_DECOUPLING
J 0
(-1375 1175);
PAINT WHITE (-1375 1175);
DISPLAY INVISIBLE (-1375 1175);
FORCEADD DESIGN_NOTE..1
(-2675 1250);
FORCEPROP 0 LAST L2 
J 0
(-2900 1025);
DISPLAY 1.021277 (-2900 1025);
PAINT ORANGE (-2900 1025);
FORCEPROP 0 LAST L1 PVNN_PCH_STBY DECOUPLING CAPS
J 0
(-2875 1125);
DISPLAY 1.063830 (-2875 1125);
PAINT WHITE (-2875 1125);
FORCEPROP 2 LAST BOM_COST SB
J 0
(-2875 1175);
DISPLAY 1.361702 (-2875 1175);
PAINT ORANGE (-2875 1175);
DISPLAY INVISIBLE (-2875 1175);
FORCEPROP 2 LAST CDS_LIB mstr_symbols
J 0
(-2675 1250);
PAINT ORANGE (-2675 1250);
DISPLAY INVISIBLE (-2675 1250);
FORCEPROP 1 LAST COMMENT_BODY TRUE
J 0
(-2650 1350);
DISPLAY 1.319149 (-2650 1350);
PAINT ORANGE (-2650 1350);
DISPLAY INVISIBLE (-2650 1350);
FORCEPROP 2 LAST ROOM SB_DECOUPLING
J 0
(-2875 1175);
DISPLAY 1.361702 (-2875 1175);
PAINT WHITE (-2875 1175);
DISPLAY INVISIBLE (-2875 1175);
FORCEADD DESIGN_NOTE..1
(2350 1000);
FORCEPROP 0 LAST L1 PVNN_PCH_STBY DECOUPLING CAPS
J 0
(2150 875);
DISPLAY 1.063830 (2150 875);
PAINT WHITE (2150 875);
FORCEPROP 2 LAST CDS_LIB mstr_symbols
J 0
(2350 1000);
PAINT ORANGE (2350 1000);
DISPLAY INVISIBLE (2350 1000);
FORCEPROP 2 LAST BOM_COST SB
J 0
(2150 925);
DISPLAY 1.361702 (2150 925);
PAINT ORANGE (2150 925);
DISPLAY INVISIBLE (2150 925);
FORCEPROP 1 LAST COMMENT_BODY TRUE
J 0
(2375 1100);
DISPLAY 1.319149 (2375 1100);
PAINT ORANGE (2375 1100);
DISPLAY INVISIBLE (2375 1100);
FORCEPROP 2 LAST ROOM SB_DECOUPLING
J 0
(2150 925);
DISPLAY 1.361702 (2150 925);
PAINT WHITE (2150 925);
DISPLAY INVISIBLE (2150 925);
FORCEADD CAD_NOTE..1
(675 975);
FORCEPROP 0 LAST L1 PLACE CAPS ON THE
J 0
(525 850);
DISPLAY 1.063830 (525 850);
PAINT WHITE (525 850);
FORCEPROP 0 LAST L2 EDGE OF THE PKG.
J 0
(525 775);
DISPLAY 1.063830 (525 775);
PAINT WHITE (525 775);
FORCEPROP 2 LAST BOM_COST SB
J 0
(525 925);
PAINT MONO (525 925);
DISPLAY INVISIBLE (525 925);
FORCEPROP 2 LAST CDS_LIB mstr_symbols
J 0
(675 975);
PAINT ORANGE (675 975);
DISPLAY INVISIBLE (675 975);
FORCEPROP 1 LAST COMMENT_BODY TRUE
J 0
(700 1075);
DISPLAY 1.319149 (700 1075);
PAINT GREEN (700 1075);
DISPLAY INVISIBLE (700 1075);
FORCEPROP 2 LAST ROOM SB_DECOUPLING
J 0
(525 925);
PAINT WHITE (525 925);
DISPLAY INVISIBLE (525 925);
FORCEADD CAD_NOTE..1
(-2575 2400);
FORCEPROP 0 LAST L2 STYLE NEAR TO PIN.
J 0
(-2725 2200);
DISPLAY 1.063830 (-2725 2200);
PAINT WHITE (-2725 2200);
FORCEPROP 0 LAST L1 PLACE CAPS BSC
J 0
(-2725 2275);
DISPLAY 1.063830 (-2725 2275);
PAINT WHITE (-2725 2275);
FORCEPROP 2 LAST CDS_LIB mstr_symbols
J 0
(-2575 2400);
PAINT ORANGE (-2575 2400);
DISPLAY INVISIBLE (-2575 2400);
FORCEPROP 2 LAST BOM_COST SB
J 0
(-2725 2350);
PAINT MONO (-2725 2350);
DISPLAY INVISIBLE (-2725 2350);
FORCEPROP 1 LAST COMMENT_BODY TRUE
J 0
(-2550 2500);
DISPLAY 1.319149 (-2550 2500);
PAINT GREEN (-2550 2500);
DISPLAY INVISIBLE (-2550 2500);
FORCEPROP 2 LAST ROOM SB_DECOUPLING
J 0
(-2725 2350);
PAINT WHITE (-2725 2350);
DISPLAY INVISIBLE (-2725 2350);
FORCEADD INTEL_CORP_BPAGE..1
(4250 200);
FORCEPROP 1 LAST CDS_CON_LAST_MODIFIED Tue Dec 01 11:52:00 2015
J 0
(2825 525);
PAINT ORANGE (2825 525);
DISPLAY INVISIBLE (2825 525);
FORCEPROP 1 LAST CUSTOM_TXT_CDS <CURRENT_DESIGN_SHEET> OF <TOTAL_DESIGN_SHEETS>
J 0
(3750 225);
PAINT GREEN (3750 225);
FORCEPROP 1 LAST CUSTOM_TXT_CDS <CON_LAST_MODIFIED>
J 0
(2325 550);
PAINT GREEN (2325 550);
FORCEPROP 2 LAST CUSTOM_TXT_CDS <XR_PAGE_TITLE>
J 0
(-3640 5450);
DISPLAY 0.638298 (-3640 5450);
PAINT PINK (-3640 5450);
DISPLAY INVISIBLE (-3640 5450);
FORCEPROP 1 LAST SCH_ADDRESS3 Santa Clara, CA 95052-8119
J 0
(275 225);
DISPLAY 0.617021 (275 225);
PAINT GREEN (275 225);
FORCEPROP 1 LAST SCH_ADDRESS2 P.O. BOX 58119
J 0
(275 275);
DISPLAY 0.617021 (275 275);
PAINT GREEN (275 275);
FORCEPROP 1 LAST SCH_ADDRESS1 2200 Mission College Blvd.
J 0
(275 325);
DISPLAY 0.617021 (275 325);
PAINT GREEN (275 325);
FORCEPROP 1 LAST SCH_TITLE PCH DECOUPLING 3/3
J 0
(-3700 250);
DISPLAY 1.212766 (-3700 250);
PAINT ORANGE (-3700 250);
FORCEPROP 1 LAST SCH_NUMBER H4694802
J 0
(2950 350);
DISPLAY 1.212766 (2950 350);
PAINT YELLOW (2950 350);
FORCEPROP 1 LAST SCH_DEPT BESD
J 1
(-200 300);
DISPLAY 1.212766 (-200 300);
PAINT YELLOW (-200 300);
FORCEPROP 1 LAST SCH_REV 2.420
J 0
(4000 350);
DISPLAY 0.978723 (4000 350);
PAINT YELLOW (4000 350);
FORCEPROP 2 LAST CDS_LIB mstr_symbols
J 0
(4250 200);
PAINT MONO (4250 200);
DISPLAY INVISIBLE (4250 200);
FORCEPROP 2 LAST PAGE_BORDER TRUE
J 0
(-3640 5450);
DISPLAY 0.638298 (-3640 5450);
PAINT PINK (-3640 5450);
DISPLAY INVISIBLE (-3640 5450);
FORCEPROP 1 LAST COMMENT_BODY TRUE
J 0
(4262 212);
DISPLAY 0.468085 (4262 212);
PAINT GREEN (4262 212);
DISPLAY INVISIBLE (4262 212);
FORCEPROP 2 LAST CDS_XR_PAGE_TITLE CR-132 : @BASEBOARD_FAB2_LIB.BASEBOARD_FAB2(SCH_1):PAGE132
J 0
(-3640 5450);
DISPLAY 0.638298 (-3640 5450);
PAINT PINK (-3640 5450);
DISPLAY INVISIBLE (-3640 5450);
WIRE 16 -1 (1075 4375)(1075 4250);
WIRE 16 -1 (1450 4250)(1075 4250);
WIRE 16 -1 (1450 4375)(1450 4250);
WIRE 16 -1 (1825 4250)(1450 4250);
WIRE 16 -1 (1825 4375)(1825 4250);
WIRE 16 -1 (2050 4250)(1825 4250);
WIRE 16 -1 (2200 4250)(2050 4250);
WIRE 16 -1 (2050 4250)(2050 4200);
WIRE 16 -1 (2575 4250)(2200 4250);
WIRE 16 -1 (2200 4375)(2200 4250);
WIRE 16 -1 (2575 4375)(2575 4250);
WIRE 16 -1 (2550 3600)(2550 3675);
WIRE 16 -1 (2550 3675)(2200 3675);
WIRE 16 -1 (2200 3600)(2200 3675);
WIRE 16 -1 (2200 3675)(1825 3675);
WIRE 16 -1 (1825 3600)(1825 3675);
WIRE 16 -1 (1825 3675)(1450 3675);
WIRE 16 -1 (1450 3600)(1450 3675);
WIRE 16 -1 (1350 3675)(1450 3675);
WIRE 16 -1 (1350 3675)(1075 3675);
WIRE 16 -1 (1350 3675)(1350 3700);
WIRE 16 -1 (1075 3600)(1075 3675);
WIRE 16 -1 (1075 3400)(1075 3275);
WIRE 16 -1 (1075 3275)(1450 3275);
WIRE 16 -1 (1450 3400)(1450 3275);
WIRE 16 -1 (1825 3275)(1450 3275);
WIRE 16 -1 (1825 3400)(1825 3275);
WIRE 16 -1 (2075 3275)(1825 3275);
WIRE 16 -1 (2075 3275)(2200 3275);
WIRE 16 -1 (2075 3275)(2075 3225);
WIRE 16 -1 (2550 3275)(2200 3275);
WIRE 16 -1 (2200 3400)(2200 3275);
WIRE 16 -1 (2550 3400)(2550 3275);
WIRE 16 -1 (2600 2625)(2600 2700);
WIRE 16 -1 (2600 2700)(2225 2700);
WIRE 16 -1 (2225 2625)(2225 2700);
WIRE 16 -1 (2225 2700)(1850 2700);
WIRE 16 -1 (1850 2625)(1850 2700);
WIRE 16 -1 (1850 2700)(1475 2700);
WIRE 16 -1 (1475 2625)(1475 2700);
WIRE 16 -1 (1400 2700)(1475 2700);
WIRE 16 -1 (1400 2700)(1100 2700);
WIRE 16 -1 (1400 2700)(1400 2725);
WIRE 16 -1 (1100 2625)(1100 2700);
WIRE 16 -1 (1100 2425)(1100 2300);
WIRE 16 -1 (1100 2300)(1475 2300);
WIRE 16 -1 (1475 2425)(1475 2300);
WIRE 16 -1 (1850 2300)(1475 2300);
WIRE 16 -1 (1850 2425)(1850 2300);
WIRE 16 -1 (2050 2300)(1850 2300);
WIRE 16 -1 (2050 2300)(2225 2300);
WIRE 16 -1 (2050 2300)(2050 2250);
WIRE 16 -1 (2600 2300)(2225 2300);
WIRE 16 -1 (2225 2425)(2225 2300);
WIRE 16 -1 (2600 2425)(2600 2300);
WIRE 16 -1 (2150 1675)(2150 1775);
WIRE 16 -1 (2150 1775)(1925 1775);
WIRE 16 -1 (1925 1775)(1700 1775);
WIRE 16 -1 (1925 1825)(1925 1775);
WIRE 16 -1 (1700 1675)(1700 1775);
WIRE 16 -1 (2150 1475)(2150 1325);
WIRE 16 -1 (2150 1325)(1925 1325);
WIRE 16 -1 (1925 1325)(1700 1325);
WIRE 16 -1 (1925 1325)(1925 1250);
WIRE 16 -1 (1700 1475)(1700 1325);
WIRE 16 -1 (-3400 3950)(-3400 3825);
WIRE 16 -1 (-3400 3825)(-3000 3825);
WIRE 16 -1 (-3000 3950)(-3000 3825);
WIRE 16 -1 (-2625 3825)(-3000 3825);
WIRE 16 -1 (-2625 3950)(-2625 3825);
WIRE 16 -1 (-2225 3825)(-2625 3825);
WIRE 16 -1 (-2225 3950)(-2225 3825);
WIRE 16 -1 (-1850 3825)(-2225 3825);
WIRE 16 -1 (-1850 3950)(-1850 3825);
WIRE 16 -1 (-1850 3825)(-1750 3825);
WIRE 16 -1 (-1750 3825)(-1475 3825);
WIRE 16 -1 (-1750 3825)(-1750 3800);
WIRE 16 -1 (-1475 3825)(-1100 3825);
WIRE 16 -1 (-1475 3950)(-1475 3825);
WIRE 16 -1 (-725 3825)(-1100 3825);
WIRE 16 -1 (-1100 3950)(-1100 3825);
WIRE 16 -1 (-325 3825)(-725 3825);
WIRE 16 -1 (-725 3950)(-725 3825);
WIRE 16 -1 (-325 3950)(-325 3825);
WIRE 16 -1 (-3375 2925)(-3375 2800);
WIRE 16 -1 (-3375 2800)(-2975 2800);
WIRE 16 -1 (-2975 2925)(-2975 2800);
WIRE 16 -1 (-2600 2800)(-2975 2800);
WIRE 16 -1 (-2600 2925)(-2600 2800);
WIRE 16 -1 (-2200 2800)(-2600 2800);
WIRE 16 -1 (-2200 2925)(-2200 2800);
WIRE 16 -1 (-1825 2800)(-2200 2800);
WIRE 16 -1 (-1825 2925)(-1825 2800);
WIRE 16 -1 (-1825 2800)(-1725 2800);
WIRE 16 -1 (-1725 2800)(-1450 2800);
WIRE 16 -1 (-1725 2800)(-1725 2775);
WIRE 16 -1 (-1450 2800)(-1075 2800);
WIRE 16 -1 (-1450 2925)(-1450 2800);
WIRE 16 -1 (-700 2800)(-1075 2800);
WIRE 16 -1 (-1075 2925)(-1075 2800);
WIRE 16 -1 (-300 2800)(-700 2800);
WIRE 16 -1 (-700 2925)(-700 2800);
WIRE 16 -1 (-300 2925)(-300 2800);
WIRE 16 -1 (-650 2000)(-650 2100);
WIRE 16 -1 (-650 2100)(-875 2100);
WIRE 16 -1 (-875 2100)(-1100 2100);
WIRE 16 -1 (-875 2150)(-875 2100);
WIRE 16 -1 (-1100 2000)(-1100 2100);
WIRE 16 -1 (-650 1800)(-650 1650);
WIRE 16 -1 (-650 1650)(-875 1650);
WIRE 16 -1 (-875 1650)(-1100 1650);
WIRE 16 -1 (-875 1650)(-875 1575);
WIRE 16 -1 (-1100 1800)(-1100 1650);
WIRE 16 -1 (-325 4225)(-325 4150);
WIRE 16 -1 (-725 4225)(-325 4225);
WIRE 16 -1 (-725 4150)(-725 4225);
WIRE 16 -1 (-1100 4225)(-725 4225);
WIRE 16 -1 (-1100 4150)(-1100 4225);
WIRE 16 -1 (-1100 4225)(-1475 4225);
WIRE 16 -1 (-1475 4150)(-1475 4225);
WIRE 16 -1 (-1850 4225)(-1475 4225);
WIRE 16 -1 (-1850 4150)(-1850 4225);
WIRE 16 -1 (-1850 4225)(-2225 4225);
WIRE 16 -1 (-2225 4150)(-2225 4225);
WIRE 16 -1 (-2225 4225)(-2625 4225);
WIRE 16 -1 (-2625 4150)(-2625 4225);
WIRE 16 -1 (-2625 4225)(-3000 4225);
WIRE 16 -1 (-3000 4150)(-3000 4225);
WIRE 16 -1 (-3225 4225)(-3000 4225);
WIRE 16 -1 (-3400 4225)(-3225 4225);
WIRE 16 -1 (-3225 4225)(-3225 4250);
WIRE 16 -1 (-3400 4150)(-3400 4225);
WIRE 16 -1 (2575 4625)(2575 4575);
WIRE 16 -1 (2575 4625)(2200 4625);
WIRE 16 -1 (2200 4575)(2200 4625);
WIRE 16 -1 (2200 4625)(1825 4625);
WIRE 16 -1 (1825 4575)(1825 4625);
WIRE 16 -1 (1825 4625)(1450 4625);
WIRE 16 -1 (1450 4575)(1450 4625);
WIRE 16 -1 (1450 4625)(1350 4625);
WIRE 16 -1 (1075 4625)(1350 4625);
WIRE 16 -1 (1350 4675)(1350 4625);
WIRE 16 -1 (1075 4575)(1075 4625);
WIRE 16 -1 (-300 3200)(-300 3125);
WIRE 16 -1 (-700 3200)(-300 3200);
WIRE 16 -1 (-700 3125)(-700 3200);
WIRE 16 -1 (-1075 3200)(-700 3200);
WIRE 16 -1 (-1075 3125)(-1075 3200);
WIRE 16 -1 (-1075 3200)(-1450 3200);
WIRE 16 -1 (-1450 3125)(-1450 3200);
WIRE 16 -1 (-1825 3200)(-1450 3200);
WIRE 16 -1 (-1825 3125)(-1825 3200);
WIRE 16 -1 (-1825 3200)(-2200 3200);
WIRE 16 -1 (-2200 3125)(-2200 3200);
WIRE 16 -1 (-2200 3200)(-2600 3200);
WIRE 16 -1 (-2600 3125)(-2600 3200);
WIRE 16 -1 (-2600 3200)(-2975 3200);
WIRE 16 -1 (-2975 3125)(-2975 3200);
WIRE 16 -1 (-3200 3200)(-2975 3200);
WIRE 16 -1 (-3375 3200)(-3200 3200);
WIRE 16 -1 (-3200 3200)(-3200 3225);
WIRE 16 -1 (-3375 3125)(-3375 3200);
WIRE 16 -1 (-2950 2100)(-2550 2100);
WIRE 16 -1 (-2950 2025)(-2950 2100);
WIRE 16 -1 (-2950 2100)(-3150 2100);
WIRE 16 -1 (-2550 2100)(-2550 2025);
WIRE 16 -1 (-3425 2100)(-3150 2100);
WIRE 16 -1 (-3150 2150)(-3150 2100);
WIRE 16 -1 (-3425 2025)(-3425 2100);
WIRE 16 -1 (-2550 1825)(-2550 1700);
WIRE 16 -1 (-2550 1700)(-2950 1700);
WIRE 16 -1 (-2950 1825)(-2950 1700);
WIRE 16 -1 (-3100 1700)(-2950 1700);
WIRE 16 -1 (-3100 1700)(-3425 1700);
WIRE 16 -1 (-3100 1700)(-3100 1650);
WIRE 16 -1 (-3425 1825)(-3425 1700);
WIRE 16 273 (225 5125)(225 650);
DOT 1 (-3225 4225);
DOT 1 (-2950 2100);
DOT 1 (-3150 2100);
DOT 1 (-2950 1700);
DOT 1 (-2200 2800);
DOT 1 (-875 1650);
DOT 1 (-3100 1700);
DOT 1 (-2975 2800);
DOT 1 (-3200 3200);
DOT 1 (-2975 3200);
DOT 1 (-2600 2800);
DOT 1 (-2600 3200);
DOT 1 (-2200 3200);
DOT 1 (-2625 3825);
DOT 1 (-2625 4225);
DOT 1 (-2225 3825);
DOT 1 (-2225 4225);
DOT 1 (-875 2100);
DOT 1 (-1825 2800);
DOT 1 (-1725 2800);
DOT 1 (-1450 2800);
DOT 1 (-1825 3200);
DOT 1 (-1450 3200);
DOT 1 (-1075 2800);
DOT 1 (-1075 3200);
DOT 1 (-1850 3825);
DOT 1 (-1750 3825);
DOT 1 (-1475 3825);
DOT 1 (-1850 4225);
DOT 1 (-1475 4225);
DOT 1 (-1100 3825);
DOT 1 (-1100 4225);
DOT 1 (-700 2800);
DOT 1 (-700 3200);
DOT 1 (-725 3825);
DOT 1 (-725 4225);
DOT 1 (1925 1325);
DOT 1 (1925 1775);
DOT 1 (2050 2300);
DOT 1 (1850 2300);
DOT 1 (1475 2300);
DOT 1 (1400 2700);
DOT 1 (1475 2700);
DOT 1 (1450 3275);
DOT 1 (1850 2700);
DOT 1 (1825 3275);
DOT 1 (2075 3275);
DOT 1 (2200 3275);
DOT 1 (1350 3675);
DOT 1 (1450 3675);
DOT 1 (1450 4250);
DOT 1 (1825 3675);
DOT 1 (2200 3675);
DOT 1 (1825 4250);
DOT 1 (2050 4250);
DOT 1 (2200 4250);
DOT 1 (2225 2300);
DOT 1 (2225 2700);
DOT 1 (1350 4625);
DOT 1 (1450 4625);
DOT 1 (1825 4625);
DOT 1 (2200 4625);
DOT 1 (-3000 4225);
DOT 1 (-3000 3825);
FORCENOTE
BOM_COST=SB
(-1775 475) 0;
DISPLAY LEFT (-1775 475);
DISPLAY 1.723404 (-1775 475);
PAINT PURPLE (-1775 475);
FORCENOTE
ROOM=SB_DECOUPLING
(-3450 475) 0;
DISPLAY LEFT (-3450 475);
DISPLAY 1.723404 (-3450 475);
PAINT PURPLE (-3450 475);
QUIT
